# Lightning_PEB_EQL.xlsx — LepoardRaiselength (si-constraints)
| LEOPARD-2SLOT-RISER-BRD-FAB2-0715.brd |  |  |  |
| Date Sun Nov 15 15:08:23 2015 |  |  |  |
| Net Name | Etch Length (mils) | Manhattan Length (mils) | Percent Manhattan (mils) |
| CLK100_PCIE_SLOT0_N | 2681.04 | 2906.67 | 92.24 |
| CLK100_PCIE_SLOT0_P | 2681.56 | 2827.93 | 94.82 |
| CLK100_PCIE_SLOT1_N | 3378.54 | 3238.95 | 104.31 |
| CLK100_PCIE_SLOT1_P | 3378.71 | 3160.21 | 106.91 |
| CLK100_PCIE_SLOT_N | 338.17 | 379.57 | 89.09 |
| CLK100_PCIE_SLOT_P | 334.87 | 341.94 | 97.93 |
| GND | 14809.44 | 31217.93 | 47.44 |
| LAN_SMB_ALERT_N | 2873.18 | 2928.81 | 98.1 |
| LAN_SMB_CLK | 2906.43 | 3306.67 | 87.9 |
| LAN_SMB_DAT | 3015.4 | 3311.04 | 91.07 |
| MB_PD_SLOT_PRSNT | 3322.06 | 3214.73 | 103.34 |
| P12V | 1996.42 | 5010.03 | 39.85 |
| P3V3 | 1405.95 | 4223.29 | 33.29 |
| P3V3_AUX | 1290.42 | 3865.07 | 33.39 |
| PCH_PLTRST_N | 2802.89 | 2976.93 | 94.15 |
| PCIE_CPRSNT_N | 275.64 | 325.17 | 84.77 |
| PCIE_SLOT0_CPRSNT1_N | 2626.35 | 2876.98 | 91.29 |
| PCIE_SLOT0_CPRSNT2_N | 2758.86 | 2916.35 | 94.6 |
| PCIE_SLOT0_RXN0 | 2289.88 | 2434.2199999999998 | 94.07 |
| PCIE_SLOT0_RXN1 | 2194.52 | 2512.96 | 87.33 |
| PCIE_SLOT0_RXN2 | 2185.9699999999998 | 2512.96 | 86.99 |
| PCIE_SLOT0_RXN3 | 2194.87 | 2512.96 | 87.34 |
| PCIE_SLOT0_RXN4 | 2194.9499999999998 | 2512.96 | 87.35 |
| PCIE_SLOT0_RXN5 | 2195.34 | 2512.96 | 87.36 |
| PCIE_SLOT0_RXN6 | 2194.4 | 2512.96 | 87.32 |
| PCIE_SLOT0_RXN7 | 2195.2600000000002 | 2512.96 | 87.36 |
| PCIE_SLOT0_RXP0 | 2289.0300000000002 | 2512.96 | 91.09 |
| PCIE_SLOT0_RXP1 | 2194.35 | 2434.2199999999998 | 90.15 |
| PCIE_SLOT0_RXP2 | 2185.4899999999998 | 2434.2199999999998 | 89.78 |
| PCIE_SLOT0_RXP3 | 2193.9699999999998 | 2434.2199999999998 | 90.13 |
| PCIE_SLOT0_RXP4 | 2194.6999999999998 | 2434.2199999999998 | 90.16 |
| PCIE_SLOT0_RXP5 | 2194.62 | 2434.2199999999998 | 90.16 |
| PCIE_SLOT0_RXP6 | 2194.19 | 2434.2199999999998 | 90.14 |
| PCIE_SLOT0_RXP7 | 2194.52 | 2434.2199999999998 | 90.15 |
| PCIE_SLOT0_TXN0 | 2065.5100000000002 | 2325.8000000000002 | 88.81 |
| PCIE_SLOT0_TXN1 | 2015.44 | 2247.06 | 89.69 |
| PCIE_SLOT0_TXN2 | 1992.69 | 2247.06 | 88.68 |
| PCIE_SLOT0_TXN3 | 1997.81 | 2247.06 | 88.91 |
| PCIE_SLOT0_TXN4 | 1998.36 | 2247.06 | 88.93 |
| PCIE_SLOT0_TXN5 | 1993.86 | 2247.06 | 88.73 |
| PCIE_SLOT0_TXN6 | 1987.48 | 2247.06 | 88.45 |
| PCIE_SLOT0_TXN7 | 1990.41 | 2247.06 | 88.58 |
| PCIE_SLOT0_TXP0 | 2065.15 | 2247.06 | 91.9 |
| PCIE_SLOT0_TXP1 | 2016.37 | 2325.8000000000002 | 86.7 |
| PCIE_SLOT0_TXP2 | 1993.17 | 2325.8000000000002 | 85.7 |
| PCIE_SLOT0_TXP3 | 1997.07 | 2325.8000000000002 | 85.87 |
| PCIE_SLOT0_TXP4 | 1997.83 | 2325.8000000000002 | 85.9 |
| PCIE_SLOT0_TXP5 | 1994.49 | 2325.8000000000002 | 85.75 |
| PCIE_SLOT0_TXP6 | 1988.39 | 2325.8000000000002 | 85.49 |
| PCIE_SLOT0_TXP7 | 1991.23 | 2325.8000000000002 | 85.61 |
| PCIE_SLOT1_CPRSNT1_N | 4335.08 | 3524.23 | 123.01 |
| PCIE_SLOT1_CPRSNT2_N | 3053.24 | 3524.23 | 86.64 |
| PCIE_SLOT1_CPRSNT3_N | 2974.36 | 3642.33 | 81.66 |
| PCIE_SLOT1_RXN0 | 3974.95 | 3829.5 | 103.8 |
| PCIE_SLOT1_RXN1 | 3823.75 | 3868.87 | 98.83 |
| PCIE_SLOT1_RXN2 | 3741.1 | 3868.87 | 96.7 |
| PCIE_SLOT1_RXN3 | 3667.05 | 3868.87 | 94.78 |
| PCIE_SLOT1_RXN4 | 3499.05 | 3790.13 | 92.32 |
| PCIE_SLOT1_RXN5 | 3400.12 | 3790.13 | 89.71 |
| PCIE_SLOT1_RXN6 | 3311.77 | 3790.13 | 87.38 |
| PCIE_SLOT1_RXN7 | 3223.97 | 3790.13 | 85.06 |
| PCIE_SLOT1_RXN8 | 3179.37 | 3711.39 | 85.67 |
| PCIE_SLOT1_RXN9 | 3147.28 | 3711.39 | 84.8 |
| PCIE_SLOT1_RXN10 | 3138.37 | 3711.39 | 84.56 |
| PCIE_SLOT1_RXN11 | 3140.56 | 3711.39 | 84.62 |
| PCIE_SLOT1_RXN12 | 3140.06 | 3711.39 | 84.61 |
| PCIE_SLOT1_RXN13 | 3141.98 | 3711.39 | 84.66 |
| PCIE_SLOT1_RXN14 | 3140.52 | 3711.39 | 84.62 |
| PCIE_SLOT1_RXN15 | 3140.62 | 3711.38 | 84.62 |
| PCIE_SLOT1_RXP0 | 3975.79 | 3908.24 | 101.73 |
| PCIE_SLOT1_RXP1 | 3822.81 | 3790.13 | 100.86 |
| PCIE_SLOT1_RXP2 | 3740.33 | 3790.13 | 98.69 |
| PCIE_SLOT1_RXP3 | 3666.1 | 3790.13 | 96.73 |
| PCIE_SLOT1_RXP4 | 3498.86 | 3711.39 | 94.27 |
| PCIE_SLOT1_RXP5 | 3399.85 | 3711.39 | 91.61 |
| PCIE_SLOT1_RXP6 | 3311.68 | 3711.39 | 89.23 |
| PCIE_SLOT1_RXP7 | 3224.11 | 3711.39 | 86.87 |
| PCIE_SLOT1_RXP8 | 3179.11 | 3790.13 | 83.88 |
| PCIE_SLOT1_RXP9 | 3147.85 | 3790.13 | 83.05 |
| PCIE_SLOT1_RXP10 | 3139.23 | 3790.13 | 82.83 |
| PCIE_SLOT1_RXP11 | 3140.77 | 3790.13 | 82.87 |
| PCIE_SLOT1_RXP12 | 3140.8 | 3790.13 | 82.87 |
| PCIE_SLOT1_RXP13 | 3142.67 | 3790.13 | 82.92 |
| PCIE_SLOT1_RXP14 | 3141.09 | 3790.13 | 82.88 |
| PCIE_SLOT1_RXP15 | 3141.42 | 3790.13 | 82.88 |
| PCIE_SLOT1_TXN0 | 3972.08 | 3721.08 | 106.75 |
| PCIE_SLOT1_TXN1 | 3806.2 | 3602.97 | 105.64 |
| PCIE_SLOT1_TXN2 | 3688.05 | 3602.97 | 102.36 |
| PCIE_SLOT1_TXN3 | 3628.42 | 3602.97 | 100.71 |
| PCIE_SLOT1_TXN4 | 3478.84 | 3524.23 | 98.71 |
| PCIE_SLOT1_TXN5 | 3423.43 | 3524.23 | 97.14 |
| PCIE_SLOT1_TXN6 | 3291.32 | 3524.23 | 93.39 |
| PCIE_SLOT1_TXN7 | 3191.29 | 3524.23 | 90.55 |
| PCIE_SLOT1_TXN8 | 3129.09 | 3602.97 | 86.85 |
| PCIE_SLOT1_TXN9 | 3058.39 | 3602.97 | 84.89 |
| PCIE_SLOT1_TXN10 | 2997.3 | 3602.97 | 83.19 |
| PCIE_SLOT1_TXN11 | 2957.31 | 3602.97 | 82.08 |
| PCIE_SLOT1_TXN12 | 2939.76 | 3602.97 | 81.59 |
| PCIE_SLOT1_TXN13 | 2939.18 | 3602.97 | 81.58 |
| PCIE_SLOT1_TXN14 | 2947.56 | 3602.97 | 81.81 |
| PCIE_SLOT1_TXN15 | 2988.58 | 3602.97 | 82.95 |
| PCIE_SLOT1_TXP0 | 3972 | 3642.34 | 109.05 |
| PCIE_SLOT1_TXP1 | 3807.17 | 3681.71 | 103.41 |
| PCIE_SLOT1_TXP2 | 3688.53 | 3681.71 | 100.19 |
| PCIE_SLOT1_TXP3 | 3628.79 | 3681.71 | 98.56 |
| PCIE_SLOT1_TXP4 | 3479.79 | 3602.97 | 96.58 |
| PCIE_SLOT1_TXP5 | 3423.88 | 3602.97 | 95.03 |
| PCIE_SLOT1_TXP6 | 3291.3 | 3602.97 | 91.35 |
| PCIE_SLOT1_TXP7 | 3192.23 | 3602.97 | 88.6 |
| PCIE_SLOT1_TXP8 | 3129.06 | 3524.23 | 88.79 |
| PCIE_SLOT1_TXP9 | 3057.79 | 3524.23 | 86.76 |
| PCIE_SLOT1_TXP10 | 2996.36 | 3524.23 | 85.02 |
| PCIE_SLOT1_TXP11 | 2956.5 | 3524.23 | 83.89 |
| PCIE_SLOT1_TXP12 | 2938.85 | 3524.23 | 83.39 |
| PCIE_SLOT1_TXP13 | 2938.6 | 3524.23 | 83.38 |
| PCIE_SLOT1_TXP14 | 2946.58 | 3524.23 | 83.61 |
| PCIE_SLOT1_TXP15 | 2987.64 | 3524.23 | 84.77 |
| PCIE_SMCLK | 2091.1999999999998 | 2228.75 | 93.83 |
| PCIE_SMCLK0 | 182.6 | 178.6 | 102.24 |
| PCIE_SMCLK1 | 136.75 | 157.6 | 86.77 |
| PCIE_SMDAT | 2081.6999999999998 | 2214.98 | 93.98 |
| PCIE_SMDAT0 | 184.2 | 173.6 | 106.1 |
| PCIE_SMDAT1 | 142.85 | 168.8 | 84.63 |
| PCIE_WAKE_N | 3225.63 | 3125.81 | 103.19 |
| PERST_N | 1255.1600000000001 | 1169.56 | 107.32 |
| PERST_N_1 | 253.2 | 254.4 | 99.53 |
| PERST_N_1_R | 263.2 | 140 | 188 |
| PERST_O_1_R | 192.28 | 214.4 | 89.68 |
| PERST_O_2_R | 170.61 | 179.4 | 95.1 |
| RESET_IN | 178.91 | 191.5 | 93.42 |
| RESET_O_1 | 126.89 | 163.5 | 77.61 |
| RESET_O_2 | 68.91 | 81.5 | 84.55 |
| RESET_P3V3_IN | 215.51 | 161.5 | 133.44 |
| RSVD0 | 311.63 | 316.58999999999997 | 98.43 |
| RSVD1 | 341.71 | 360.22 | 94.86 |
| S0_PCIE_SMCLK | 455.63 | 454.66 | 100.21 |
| S0_PCIE_SMDAT | 374.76 | 376.55 | 99.52 |
| S0_SMB_ALERT_B12_N | 123.68 | 127.59 | 96.94 |
| S0_SMB_CLK_A32 | 524.32000000000005 | 612.91 | 85.55 |
| S0_SMB_DAT_A33 | 667.3 | 776.02 | 85.99 |
| S1_PCIE_SMCLK | 1665.77 | 1294.6600000000001 | 128.66 |
| S1_PCIE_SMDAT | 1602.57 | 1168.29 | 137.16999999999999 |
| S1_SMB_ALERT_B12_N | 273 | 351.59 | 77.650000000000006 |
| S1_SMB_CLK_A32 | 1417.48 | 1117.55 | 126.84 |
| S1_SMB_DAT_A33 | 1311.73 | 1033.18 | 126.96 |
| SLOT0_CONFIG | 1513.32 | 1775.75 | 85.22 |
| SLOT0_ID_0 | 238.96 | 234 | 102.12 |
| SLOT0_ID_1 | 142.6 | 178.91 | 79.7 |
| SLOT1_CONFIG | 1473.82 | 1656.7 | 88.96 |
| SLOT1_ID_0 | 1150.33 | 1041.8399999999999 | 110.41 |
| SLOT1_ID_1 | 156.81 | 184.93 | 84.79 |
| BMC_I2C_C_SDA | 4248.8500000000004 | 4065.78 | 104.5 |
| BMC_I2C_D_SCL | 11636.63 | 9291.84 | 125.23 |
| BMC_I2C_D_SDA | 11706.54 | 9521.84 | 122.94 |
| BMC_I2C_SCL_9 | 10169.74 | 10653.44 | 95.46 |
| BMC_I2C_SCL_10 | 72.47 | 79.98 | 90.61 |
| BMC_I2C_SCL_11 | 167.01 | 126.49 | 132.04 |
| BMC_I2C_SCL_12 | 176.28 | 111.53 | 158.06 |
| BMC_I2C_SCL_11_R | 4197.9399999999996 | 2962.25 | 141.71 |
| BMC_I2C_SCL_12_R | 4053.84 | 2499.25 | 162.19999999999999 |
| BMC_I2C_SCL_BUF_11 | 3595.38 | 3527.2 | 101.93 |
| BMC_I2C_SCL_BUF_12 | 3506.51 | 3854.14 | 90.98 |
| BMC_I2C_SDA_9 | 9798.75 | 10586.04 | 92.56 |
| BMC_I2C_SDA_10 | 69.36 | 72.48 | 95.7 |
| BMC_I2C_SDA_11 | 144.44 | 117.72 | 122.7 |
| BMC_I2C_SDA_12 | 155.53 | 115.22 | 134.97999999999999 |
| BMC_I2C_SDA_11_R | 4414.7 | 2893.25 | 152.59 |
| BMC_I2C_SDA_12_R | 4003.45 | 2536.75 | 157.82 |
| BMC_I2C_SDA_BUF_11 | 3063.11 | 3633.7 | 84.3 |
| BMC_I2C_SDA_BUF_12 | 3612.93 | 3810.63 | 94.81 |
| BMC_ID_LED | 8790.34 | 8648.0499999999993 | 101.65 |
| BMC_ID_LED_R | 83.63 | 97.62 | 85.67 |
| BMC_JTAG_L_EN | 3210.58 | 3670.37 | 87.47 |
| BMC_JTAG_L_EN_R | 405.59 | 520.57000000000005 | 77.91 |
| BMC_RXD5 | 8542.56 | 7934.03 | 107.67 |
| BMC_RXD5_R | 651.5 | 686 | 94.97 |
| BMC_R_RXD5 | 139.57 | 142.5 | 97.94 |
| BMC_R_TXD5 | 144.75 | 155 | 93.39 |
| BMC_SELF_TRAY | 5906.11 | 5026 | 117.51 |
| BMC_SELF_TRAY_R | 197.64 | 202.89 | 97.41 |
| BMC_TXD5 | 8119.26 | 7637.83 | 106.3 |
| BMC_TXD5_R | 802.34 | 855.5 | 93.79 |
| BMC_USB2_HDN | 655.01 | 821.57 | 79.73 |
| BMC_USB2_HDP | 656.63 | 740.08 | 88.72 |
| CABLE1_PRSNT_N | 7956.47 | 8347.48 | 95.32 |
| CABLE2_PRSNT_N | 8043.04 | 8743.5499999999993 | 91.99 |
| CABLE3_PRSNT_N | 9561.59 | 9013.6200000000008 | 106.08 |
| CABLE4_PRSNT_N | 9623.99 | 9220.7099999999991 | 104.37 |
| CLK0431_ADR_BIT | 209.5 | 234.4 | 89.38 |
| CLK0431_SS_DIS | 182.83 | 207.6 | 88.07 |
| CLKBUF1_100M_SEL | 147.38999999999999 | 168.72 | 87.36 |
| CLKBUF1_HIBW_SEL | 141.04 | 138.4 | 101.91 |
| CLKBUF1_SMB_A0_TRI | 243.52 | 280.58999999999997 | 86.79 |
| CLKBUF1_SMB_A1_TRI | 240.56 | 274.02999999999997 | 87.79 |
| CLKBUF_OE_DISABLE | 360.23 | 919.52 | 39.18 |
| CLKBUF_OE_ENABLE | 337.86 | 238.7 | 141.54 |
| CLK_100M_MINISAS_A_DN | 4701.1000000000004 | 4723.93 | 99.52 |
| CLK_100M_MINISAS_A_DP | 4702.46 | 4737.71 | 99.26 |
| CLK_100M_MINISAS_B_DN | 5010.17 | 4094.01 | 122.38 |
| CLK_100M_MINISAS_B_DP | 5010.34 | 4107.79 | 121.97 |
| CLK_100M_MINISAS_C_DN | 4027.68 | 3542.83 | 113.69 |
| CLK_100M_MINISAS_C_DP | 4026.22 | 3556.6 | 113.2 |
| CLK_100M_MINISAS_D_DN | 3406.02 | 3188.5 | 106.82 |
| CLK_100M_MINISAS_D_DP | 3404.57 | 3202.27 | 106.32 |
| DACRSET | 667.18 | 741.53 | 89.97 |
| DDR_VREF | 2625.21 | 1537.5 | 170.75 |
| DIVIDER 1_IN | 237.96 | 217.5 | 109.41 |
| DIVIDER 2_IN | 170.78 | 82.5 | 207.01 |
| DPB_HW_REVISION | 6024.85 | 5137.91 | 117.26 |
| DP_RST_N | 9832.86 | 9954.08 | 98.78 |
| DP_RST_N_R | 620.53 | 649.41999999999996 | 95.55 |
| DR0_EXP_ADDRBIT0 | 148.41 | 160.99 | 92.18 |
| DR0_EXP_ADDRBIT1 | 144.75 | 152.16999999999999 | 95.13 |
| DR0_EXP_ADDRBIT2 | 152.79 | 171.58 | 89.05 |
| DR0_ID0 | 140.72 | 142.44 | 98.8 |
| DR0_ID1 | 148.76 | 161.85 | 91.91 |
| DR0_ID2 | 111.8 | 136.26 | 82.05 |
| DR0_ID3 | 103.76 | 116.85 | 88.8 |
| DR0_ID4 | 95.72 | 97.44 | 98.24 |
| DR3_EXP_ADDBIT0 | 148.41 | 160.99 | 92.18 |
| DR3_EXP_ADDBIT1 | 144.75 | 152.16999999999999 | 95.13 |
| DR3_EXP_ADDBIT2 | 152.79 | 171.58 | 89.05 |
| DR3_ID0 | 140.72 | 142.44 | 98.8 |
| DR3_ID1 | 148.76 | 161.85 | 91.91 |
| DR3_ID2 | 111.8 | 136.26 | 82.05 |
| DR3_ID3 | 103.76 | 116.85 | 88.8 |
| DR3_ID4 | 95.72 | 97.44 | 98.24 |
| DR4_EXP_ADDRBIT0 | 148.41 | 160.99 | 92.18 |
| DR4_EXP_ADDRBIT1 | 144.75 | 152.16999999999999 | 95.13 |
| DR4_EXP_ADDRBIT2 | 152.79 | 171.58 | 89.05 |
| DR4_ID0 | 140.72 | 142.44 | 98.8 |
| DR4_ID1 | 148.76 | 161.85 | 91.91 |
| DR4_ID2 | 111.8 | 136.26 | 82.05 |
| DR4_ID3 | 103.76 | 116.85 | 88.8 |
| DR4_ID4 | 95.72 | 97.44 | 98.24 |
| DR5_EXP_ADDRBIT0 | 148.41 | 160.99 | 92.18 |
| DR5_EXP_ADDRBIT1 | 144.75 | 152.16999999999999 | 95.13 |
| DR5_EXP_ADDRBIT2 | 152.79 | 171.58 | 89.05 |
| DR5_ID0 | 140.72 | 142.44 | 98.8 |
| DR5_ID1 | 148.76 | 161.85 | 91.91 |
| DR5_ID2 | 111.8 | 136.26 | 82.05 |
| DR5_ID3 | 103.76 | 116.85 | 88.8 |
| DR5_ID4 | 95.72 | 97.44 | 98.24 |
| EEPROM_A0_R | 251.43 | 222.5 | 113 |
| EEPROM_A1_R | 247.82 | 222.5 | 111.38 |
| EEPROM_A2_R | 270.48 | 232.5 | 116.34 |
| EEPROM_SCL | 102.5 | 110.02 | 93.16 |
| EEPROM_SDA | 106.64 | 120.02 | 88.85 |
| EEPROM_WP | 114.92 | 140.02000000000001 | 82.08 |
| EE_SDO | 3128.9 | 3406.28 | 91.86 |
| EE_SPI_CLK | 3068.35 | 3474.51 | 88.31 |
| EE_SPI_CS | 3526.82 | 3828.72 | 92.11 |
| EE_SPI_SDI | 3861.53 | 3021.24 | 127.81 |
| ENCLO_LED_BLUE_OUT | 134.76 | 134.4 | 100.26 |
| ENCLO_LED_RED_D | 268.37 | 283.75 | 94.58 |
| ENCLO_LED_RED_D1 | 746.28 | 700.16 | 106.59 |
| ENCLO_LED_RED_G | 152.16 | 158.75 | 95.85 |
| ENCLO_LED_RED_R | 631.58000000000004 | 720.96 | 87.6 |
| EXP_BMC_HB_LED_D | 1262.98 | 1447.5 | 87.25 |
| EXP_BMC_HB_LED_R | 60 | 60 | 100 |
| EXP_BMC_HB_LED_R1 | 142.43 | 100 | 142.43 |
| EXP_BMC_HB_LED_R2 | 142.43 | 100 | 142.43 |
| EXP_BMC_HB_LED_R3 | 370.46 | 200 | 185.23 |
| EXP_BMC_HB_LED_R4 | 60 | 0 | 1.#J |
| EXP_TRAY_ID | 6345.35 | 4472.5200000000004 | 141.87 |
| EXP_TRAY_ID_BMC | 1157.7 | 881.39 | 131.35 |
| FAN_PWM_PCIE_BMC_A | 515.08000000000004 | 467.54 | 110.17 |
| FCB_HW_REVISION | 5984.4 | 5137.91 | 116.48 |
| FLA_CS | 11668.27 | 11166.46 | 104.49 |
| FLA_CS_R | 418.32 | 411.77 | 101.59 |
| FLA_WPN | 207.75 | 123.39 | 168.37 |
| FM_BMC_RESET_N | 7108.06 | 6417.48 | 110.76 |
| FM_DR_RESET_OUT | 5786.37 | 6875.25 | 84.16 |
| FM_PEX2_PERST_N | 15604.91 | 6660.65 | 234.29 |
| FM_PEX2_PERST_N_R | 75.25 | 75.599999999999994 | 99.54 |
| FM_PEX_RESET_N | 1577.06 | 1362.16 | 115.78 |
| FM_PEX_RESET_N_R | 75.25 | 75.599999999999994 | 99.54 |
| HB_A_IN | 565 | 380 | 148.68 |
| HB_A_OUT | 514.38 | 452.5 | 113.68 |
| HB_OUT | 6978.57 | 5896.09 | 118.36 |
| HB_OUT_BMC | 2366.14 | 2387.5 | 99.11 |
| HB_OUT_BMC_R | 684.83 | 756.07 | 90.58 |
| HB_OUT_R | 132.25 | 162.37 | 81.45 |
| HDD0_CLK0_OE_N | 3946.02 | 5113.25 | 77.17 |
| HDD3_CLK0_OE_N | 1742.34 | 1748.73 | 99.63 |
| HDD4_CLK0_OE_N | 1250.1500000000001 | 1260.74 | 99.16 |
| HDD4_CLK0_R | 103.09 | 112.74 | 91.44 |
| HDD5_CLK0_OE_N | 3468.84 | 4562.26 | 76.03 |
| HDD_PRSNT0_R | 103.09 | 112.74 | 91.44 |
| HDD_PRSNT3_R | 103.09 | 112.74 | 91.44 |
| HDD_PRSNT5_R | 103.09 | 112.74 | 91.44 |
| HIGH_HEX_0 | 8121.93 | 8544.02 | 95.06 |
| HIGH_HEX_1 | 8757.85 | 8717.2099999999991 | 100.47 |
| HIGH_HEX_2 | 8295.6 | 8528.26 | 97.27 |
| HIGH_HEX_3 | 8344.7099999999991 | 8575.4599999999991 | 97.31 |
| HOST1_P0V9_PWRGD | 8906.86 | 6008.4 | 148.24 |
| HOST1_P0V9_PWRGD_R | 325.83 | 384.57 | 84.73 |
| HOST1_PRSNT_N | 6720.12 | 7921.84 | 84.83 |
| HOST1_PRSNT_N_R | 251.89 | 304.58999999999997 | 82.7 |
| HOST2_P0V9_PWRGD | 13767.92 | 5255.81 | 261.95999999999998 |
| HOST2_P0V9_PWRGD_R | 1377.28 | 900.15 | 153.01 |
| HOST2_PRSNT_N | 7121.64 | 8150.31 | 87.38 |
| HOST2_PRSNT_N_R | 841.64 | 757.07 | 111.17 |
| HOST3_P0V9_PWRGD | 14182.03 | 5728.89 | 247.55 |
| HOST3_P0V9_PWRGD_R | 1245.4000000000001 | 891.64 | 139.68 |
| HOST3_PRSNT_N | 7646.29 | 8587.98 | 89.03 |
| HOST3_PRSNT_N_R | 279.87 | 327.58 | 85.43 |
| HOST4_P0V9_PWRGD | 10424.24 | 7352.62 | 141.78 |
| HOST4_P0V9_PWRGD_R | 330.76 | 371.06 | 89.14 |
| HOST4_PRSNT_N | 8270.18 | 8921.0499999999993 | 92.7 |
| HOST4_PRSNT_N_R | 233.49 | 256.08 | 91.18 |
| HOST_I2C_RESET_IN | 2725.83 | 2390 | 114.05 |
| HSW_SCL_2 | 169.88 | 188.1 | 90.31 |
| HSW_SDA_2 | 188.67 | 229.21 | 82.31 |
| I2C_B_BUFF_EN | 129.02000000000001 | 104.4 | 123.58 |
| I2C_B_BUF_READY | 137.72999999999999 | 152.6 | 90.26 |
| I2C_C_BUFF_EN | 115.5 | 70.599999999999994 | 163.6 |
| I2C_C_BUF_READY | 111.2 | 67.599999999999994 | 164.5 |
| I2C_MUX_RESET_PEB | 7979.1 | 6294.41 | 126.76 |
| INVERTER_G1 | 257.77999999999997 | 269.5 | 95.65 |
| INVERTER_G2 | 145.99 | 45.7 | 319.45 |
| IOEXP_HOST_I2C_RESET_IN | 97.9 | 38.76 | 252.57 |
| IOEXP_HOST_I2C_RST_INT | 80.84 | 26.26 | 307.85000000000002 |
| IOEXP_SPARE1 | 4142.92 | 2183.9699999999998 | 189.7 |
| IOEXP_SPARE2 | 3973.94 | 2127.9699999999998 | 186.75 |
| IOEXP_SPARE1_R | 134.28 | 80.19 | 167.45 |
| IOEXP_SPARE2_R | 82.13 | 18.29 | 449.07 |
| JTAG_8780_TRST | 1764.44 | 1870.56 | 94.33 |
| JTAG_9716_SW1_TRST | 359.33 | 383.69 | 93.65 |
| JTAG_BMC_TCK | 5186.01 | 5125.3500000000004 | 101.18 |
| JTAG_BMC_TDI | 4273.0200000000004 | 4757.8100000000004 | 89.81 |
| JTAG_BMC_TDO | 5159.3599999999997 | 5281.59 | 97.69 |
| JTAG_BMC_TMS | 5422.8 | 5237.83 | 103.53 |
| JTAG_BMC_TRST_N | 5909.75 | 5977.11 | 98.87 |
| LED_PWR_N_ON | 226.8 | 218.55 | 103.77 |
| LED_PWR_N_R | 698.29 | 483.14 | 144.53 |
| LOW_HEX_0 | 8393.64 | 8669.98 | 96.81 |
| LOW_HEX_1 | 8183.88 | 8717.18 | 93.88 |
| LOW_HEX_2 | 8050.89 | 8622.7800000000007 | 93.37 |
| LOW_HEX_3 | 8314.66 | 8606.98 | 96.6 |
| MATED_P12V_EN | 300.61 | 260 | 115.62 |
| MB0_12V_CTRL_GATE1 | 113.71 | 102.5 | 110.94 |
| MB0_CM_ADR1_R | 224.68 | 280.79000000000002 | 80.02 |
| MB0_CM_ADR2_R | 239.81 | 298.10000000000002 | 80.45 |
| MB0_CM_GATE | 746.38 | 758.1 | 98.45 |
| MB0_CM_GATE_R | 297.27999999999997 | 315 | 94.37 |
| MB0_CM_OV_R | 314.49 | 400.6 | 78.5 |
| MB0_CM_SENSE_N | 211.04 | 215.79 | 97.8 |
| MB0_CM_SENSE_P | 212.97 | 234.84 | 90.69 |
| MB0_CM_SENSE_R1_N | 158.25 | 157.01 | 100.79 |
| MB0_CM_SENSE_R1_P | 156.18 | 152.01 | 102.74 |
| MB0_CM_UV_R | 262.07 | 293.29000000000002 | 89.36 |
| MB0_CM_VOUT_R | 184.92 | 180.16 | 102.64 |
| MB0_HS_ENABLE | 930.13 | 614.34 | 151.4 |
| MB0_ISET_R | 528.74 | 457.97 | 115.45 |
| MB0_ISTART_R | 281.45999999999998 | 297.66000000000003 | 94.56 |
| MB0_P12V_PWGIN_R | 172.36 | 160.16 | 107.62 |
| MB0_P12V_PWRGOOD | 3564.31 | 3507.29 | 101.63 |
| MB0_P12V_R | 95.18 | 102.5 | 92.86 |
| MB0_PSET_R | 286.01 | 313.10000000000002 | 91.35 |
| MB0_RETRY_R | 207.03 | 233.1 | 88.82 |
| MB0_SPISS_PD | 178.17 | 208.1 | 85.62 |
| MB0_TEMP | 258.27 | 302.18 | 85.47 |
| MB0_TIME_R | 224.42 | 280.16000000000003 | 80.099999999999994 |
| MB0_VCAP_R | 318.79000000000002 | 333.29 | 95.65 |
| MB0_VCC | 213.66 | 219.53 | 97.32 |
| MEMA_0 | 818.77 | 812.27 | 100.8 |
| MEMA_1 | 856.28 | 780.78 | 109.67 |
| MEMA_2 | 951.55 | 938.26 | 101.42 |
| MEMA_3 | 857.91 | 843.77 | 101.68 |
| MEMA_4 | 851.7 | 654.79 | 130.07 |
| MEMA_5 | 894.56 | 906.77 | 98.65 |
| MEMA_6 | 846.44 | 717.78 | 117.93 |
| MEMA_7 | 939.64 | 780.78 | 120.35 |
| MEMA_8 | 860.87 | 686.29 | 125.44 |
| MEMA_9 | 908.65 | 812.27 | 111.87 |
| MEMA_10 | 836.15 | 654.79 | 127.7 |
| MEMA_11 | 897.98 | 717.79 | 125.1 |
| MEMA_12 | 825.99 | 686.29 | 120.36 |
| MEMA_13 | 965.86 | 875.26 | 110.35 |
| MEMA_14 | 819.77 | 686.29 | 119.45 |
| MEMBA_0 | 958.66 | 906.77 | 105.72 |
| MEMBA_1 | 827.15 | 686.29 | 120.53 |
| MEMBA_2 | 865.51 | 843.77 | 102.58 |
| MEMCASN | 942.25 | 749.28 | 125.75 |
| MEMCKE | 823.24 | 654.79 | 125.73 |
| MEMCK_N | 693.37 | 686.29 | 101.03 |
| MEMCK_P | 691.49 | 623.29999999999995 | 110.94 |
| MEMCSN | 1001.05 | 843.78 | 118.64 |
| MEMDM_0 | 926.29 | 654.79 | 141.46 |
| MEMDM_1 | 1038.24 | 843.78 | 123.05 |
| MEMDQS_N0 | 847.77 | 780.78 | 108.58 |
| MEMDQS_N1 | 697.52 | 533.78 | 130.68 |
| MEMDQS_P0 | 839.19 | 717.78 | 116.91 |
| MEMDQS_P1 | 697.77 | 591.80999999999995 | 117.9 |
| MEMDQ_0 | 928.43 | 686.29 | 135.28 |
| MEMDQ_1 | 1012.72 | 843.77 | 120.02 |
| MEMDQ_2 | 803.97 | 528.80999999999995 | 152.03 |
| MEMDQ_3 | 921.03 | 591.80999999999995 | 155.63 |
| MEMDQ_4 | 963.35 | 780.78 | 123.38 |
| MEMDQ_5 | 1020.41 | 843.78 | 120.93 |
| MEMDQ_6 | 838.57 | 717.79 | 116.83 |
| MEMDQ_7 | 902.65 | 749.27 | 120.47 |
| MEMDQ_8 | 1029.1600000000001 | 659.78 | 155.97999999999999 |
| MEMDQ_9 | 877.81 | 533.78 | 164.45 |
| MEMDQ_10 | 862.96 | 628.28 | 137.35 |
| MEMDQ_11 | 905.93 | 722.76 | 125.34 |
| MEMDQ_12 | 931.8 | 785.76 | 118.59 |
| MEMDQ_13 | 838.31 | 628.28 | 133.43 |
| MEMDQ_14 | 857.66 | 754.25 | 113.71 |
| MEMDQ_15 | 926.19 | 817.25 | 113.33 |
| MEMODT | 1017.89 | 906.76 | 112.26 |
| MEMRASN | 995.72 | 812.28 | 122.58 |
| MEMWEN | 924.57 | 843.77 | 109.58 |
| MINISAS_RST_A_BUF_N | 3097.18 | 3556.82 | 87.08 |
| MINISAS_RST_A_N | 5421.63 | 5028.24 | 107.82 |
| MINISAS_RST_B_BUF_N | 3743.23 | 4176.1099999999997 | 89.63 |
| MINISAS_RST_B_N | 5001.6499999999996 | 4579.42 | 109.22 |
| MINISAS_RST_C_BUF_N | 1903.89 | 2354.44 | 80.86 |
| MINISAS_RST_C_N | 4484.17 | 4130.59 | 108.56 |
| MINISAS_RST_D_BUF_N | 2846.16 | 3052.48 | 93.24 |
| MINISAS_RST_D_N | 4123.3500000000004 | 3681.82 | 111.99 |
| MPLLAV33 | 852.59 | 1105.8900000000001 | 77.099999999999994 |
| N16757188 | 135.19999999999999 | 397.8 | 33.99 |
| N16816198 | 27.85 | 39.380000000000003 | 70.709999999999994 |
| N16816205 | 27.85 | 39.380000000000003 | 70.709999999999994 |
| N16816212 | 27.85 | 39.380000000000003 | 70.709999999999994 |
| N16816226 | 27.85 | 39.380000000000003 | 70.709999999999994 |
| N16817161 | 63.57 | 47.27 | 134.47999999999999 |
| N16817166 | 52.38 | 7.86 | 666.38 |
| N16817171 | 63.23 | 7.54 | 838.62 |
| N16817176 | 63.32 | 47 | 134.71 |
| N16817636 | 52.39 | 8.01 | 654.03 |
| N16817641 | 63.55 | 7.87 | 807.47 |
| N16817646 | 98.27 | 47.26 | 207.94 |
| N16817651 | 63.64 | 86.73 | 73.38 |
| N16818297 | 102.93 | 86.62 | 118.83 |
| N16818301 | 52.42 | 7.88 | 665.25 |
| N16818313 | 135.30000000000001 | 86.4 | 156.6 |
| N16818317 | 50.79 | 31.5 | 161.25 |
| N16818321 | 52.43 | 47.26 | 110.93 |
| N16818325 | 52.43 | 47.25 | 110.97 |
| N16818329 | 63.57 | 7.89 | 805.67 |
| N16818333 | 63.57 | 47.26 | 134.51 |
| N16818898 | 52.58 | 65.52 | 80.25 |
| N16818902 | 63.55 | 47.24 | 134.53 |
| N16818914 | 52.43 | 31.51 | 166.4 |
| N16818918 | 52.43 | 7.88 | 665.33 |
| N16818922 | 52.58 | 7.51 | 700.15 |
| N16818926 | 63.55 | 47.24 | 134.53 |
| N16818930 | 52.43 | 31.51 | 166.4 |
| N16818934 | 52.43 | 31.51 | 166.4 |
| N16819501 | 63.56 | 7.88 | 806.57 |
| N16819505 | 52.42 | 7.89 | 664.36 |
| N16819517 | 52.42 | 31.51 | 166.35 |
| N16819521 | 52.42 | 31.51 | 166.35 |
| N16819525 | 52.43 | 70.88 | 73.97 |
| N16819529 | 63.56 | 86.63 | 73.37 |
| N16819533 | 63.56 | 47.25 | 134.52000000000001 |
| N16819537 | 98.31 | 47.23 | 208.15 |
| N16820032 | 52.43 | 7.88 | 665.33 |
| N16820036 | 63.56 | 47.24 | 134.54 |
| N16820048 | 52.43 | 31.5 | 166.44 |
| N16820052 | 52.43 | 31.5 | 166.44 |
| N16820056 | 61.71 | 7.86 | 785.1 |
| N16820060 | 52.43 | 31.51 | 166.4 |
| N16820064 | 52.43 | 31.5 | 166.44 |
| N16820068 | 52.43 | 31.5 | 166.44 |
| N16820612 | 52.47 | 70.849999999999994 | 74.06 |
| N16820685 | 52.42 | 7.88 | 665.25 |
| N16820721 | 52.42 | 70.88 | 73.959999999999994 |
| N16820772 | 63.57 | 7.89 | 805.67 |
| N16820824 | 63.55 | 7.86 | 808.55 |
| N17111159 | 399.69 | 561.71 | 71.16 |
| N17152368 | 206.68 | 212.8 | 97.12 |
| N17152469 | 65 | 65 | 100 |
| N17152472 | 95.63 | 86.38 | 110.71 |
| N17152626 | 446.14 | 431 | 103.51 |
| N17174603 | 285.69 | 300.58 | 95.05 |
| N17174648 | 92.71 | 98.14 | 94.46 |
| N17174875 | 194.23 | 220.95 | 87.91 |
| N17175195 | 285.69 | 300.58 | 95.05 |
| N17175209 | 92.71 | 98.14 | 94.46 |
| N17176241 | 285.69 | 300.58 | 95.05 |
| N17176255 | 92.71 | 98.14 | 94.46 |
| N17176326 | 194.23 | 220.95 | 87.91 |
| N17176441 | 92.71 | 98.14 | 94.46 |
| N17178118 | 305.47000000000003 | 270.74 | 112.83 |
| N17178136 | 450.54 | 431 | 104.53 |
| N17178140 | 206.68 | 212.8 | 97.12 |
| N17178240 | 206.98 | 270.68 | 76.47 |
| N17178359 | 15 | 633.86 | 2.37 |
| N17178369 | 65 | 65 | 100 |
| N17178371 | 95.63 | 86.38 | 110.71 |
| N17178519 | 63.07 | 2.1800000000000002 | 2893.33 |
| N17178531 | 561.32000000000005 | 516.67999999999995 | 108.64 |
| N17178550 | 181.13 | 183.31 | 98.81 |
| N17180385 | 446.14 | 431 | 103.51 |
| N17180389 | 206.68 | 212.8 | 97.12 |
| N17180489 | 206.98 | 270.68 | 76.47 |
| N17180554 | 237.5 | 232.62 | 102.1 |
| N17180606 | 399.69 | 561.71 | 71.16 |
| N17180618 | 65 | 65 | 100 |
| N17180620 | 95.63 | 86.38 | 110.71 |
| N17180764 | 63.07 | 2.1800000000000002 | 2893.33 |
| N17180780 | 561.32000000000005 | 516.67999999999995 | 108.64 |
| N17180791 | 181.13 | 183.31 | 98.81 |
| N17207594 | 240.42 | 232.62 | 103.36 |
| N17207867 | 446.14 | 431 | 103.51 |
| N17207871 | 206.68 | 212.8 | 97.12 |
| N17207921 | 399.69 | 561.71 | 71.16 |
| N17207931 | 65 | 65 | 100 |
| N17207933 | 95.63 | 86.38 | 110.71 |
| N17208279 | 305.47000000000003 | 270.74 | 112.83 |
| N17208353 | 176.11 | 232.49 | 75.75 |
| N17208371 | 63.07 | 2.1800000000000002 | 2893.33 |
| N17208375 | 561.32000000000005 | 516.67999999999995 | 108.64 |
| N17208391 | 181.13 | 183.31 | 98.81 |
| N17208817 | 91.58 | 97.2 | 94.22 |
| N17208865 | 91.58 | 97.2 | 94.22 |
| N17211715 | 91.58 | 97.2 | 94.22 |
| N17281254 | 134.75 | 145.66999999999999 | 92.5 |
| N17281398 | 134.75 | 145.66999999999999 | 92.5 |
| N17282850 | 305.47000000000003 | 270.74 | 112.83 |
| N17305679 | 235.29 | 210.73 | 111.65 |
| N17306060 | 239.25 | 210.73 | 113.54 |
| N17307456 | 194.23 | 220.95 | 87.91 |
| N17307828 | 194.23 | 220.95 | 87.91 |
| N17309572 | 120.35 | 147 | 81.87 |
| N17309681 | 146.13999999999999 | 177.3 | 82.42 |
| N17332383 | 719.88 | 401 | 179.52 |
| N17332535 | 713.06 | 401 | 177.82 |
| N17343250 | 672.67 | 401 | 167.75 |
| N17383398 | 27.85 | 39.380000000000003 | 70.709999999999994 |
| N17383414 | 27.85 | 39.380000000000003 | 70.709999999999994 |
| N17383430 | 27.85 | 39.380000000000003 | 70.709999999999994 |
| N17383446 | 27.85 | 39.380000000000003 | 70.709999999999994 |
| N17383480 | 27.85 | 39.380000000000003 | 70.709999999999994 |
| N17383488 | 27.85 | 39.380000000000003 | 70.709999999999994 |
| N17383496 | 27.85 | 39.380000000000003 | 70.709999999999994 |
| N17383504 | 27.85 | 39.380000000000003 | 70.709999999999994 |
| N17383544 | 27.85 | 39.380000000000003 | 70.709999999999994 |
| N17383552 | 27.85 | 39.380000000000003 | 70.709999999999994 |
| N17383560 | 27.85 | 39.380000000000003 | 70.709999999999994 |
| N17383568 | 27.85 | 39.380000000000003 | 70.709999999999994 |
| N17383608 | 27.85 | 39.380000000000003 | 70.709999999999994 |
| N17383616 | 27.85 | 39.380000000000003 | 70.709999999999994 |
| N17383624 | 27.85 | 39.380000000000003 | 70.709999999999994 |
| N17383632 | 27.85 | 39.380000000000003 | 70.709999999999994 |
| N17383672 | 27.85 | 39.380000000000003 | 70.709999999999994 |
| N17383680 | 27.85 | 39.380000000000003 | 70.709999999999994 |
| N17383688 | 27.85 | 39.380000000000003 | 70.709999999999994 |
| N17383696 | 27.85 | 39.380000000000003 | 70.709999999999994 |
| N17383736 | 27.85 | 39.380000000000003 | 70.709999999999994 |
| N17383744 | 27.85 | 39.380000000000003 | 70.709999999999994 |
| N17383752 | 27.85 | 39.380000000000003 | 70.709999999999994 |
| N17383760 | 27.85 | 39.380000000000003 | 70.709999999999994 |
| N17383800 | 27.85 | 39.380000000000003 | 70.709999999999994 |
| N17383808 | 27.85 | 39.380000000000003 | 70.709999999999994 |
| N17383816 | 27.85 | 39.380000000000003 | 70.709999999999994 |
| N17383824 | 27.85 | 39.380000000000003 | 70.709999999999994 |
| N17383864 | 27.85 | 39.380000000000003 | 70.709999999999994 |
| N17383872 | 27.85 | 39.380000000000003 | 70.709999999999994 |
| N17383880 | 27.85 | 39.380000000000003 | 70.709999999999994 |
| N17383888 | 27.85 | 39.380000000000003 | 70.709999999999994 |
| N17383928 | 27.85 | 39.380000000000003 | 70.709999999999994 |
| N17383936 | 27.85 | 39.380000000000003 | 70.709999999999994 |
| N17383944 | 27.85 | 39.380000000000003 | 70.709999999999994 |
| N17383952 | 27.85 | 39.380000000000003 | 70.709999999999994 |
| N17384146 | 27.85 | 39.380000000000003 | 70.709999999999994 |
| N17384154 | 27.85 | 39.380000000000003 | 70.709999999999994 |
| N17384178 | 27.85 | 39.380000000000003 | 70.709999999999994 |
| N17384186 | 27.85 | 39.380000000000003 | 70.709999999999994 |
| N17384210 | 27.85 | 39.380000000000003 | 70.709999999999994 |
| N17384218 | 27.85 | 39.380000000000003 | 70.709999999999994 |
| N17384242 | 27.85 | 39.380000000000003 | 70.709999999999994 |
| N17384250 | 27.85 | 39.380000000000003 | 70.709999999999994 |
| N17712137 | 1634.16 | 1777.57 | 91.93 |
| N17713965 | 27.85 | 39.380000000000003 | 70.709999999999994 |
| N17713967 | 27.85 | 39.380000000000003 | 70.709999999999994 |
| N17713969 | 27.85 | 39.380000000000003 | 70.709999999999994 |
| N17713971 | 27.85 | 39.380000000000003 | 70.709999999999994 |
| N17785514 | 564.57000000000005 | 181.98 | 310.24 |
| N17895176 | 75.25 | 75.599999999999994 | 99.54 |
| N17945545 | 130.38 | 143.15 | 91.08 |
| N17945603 | 102.66 | 108.9 | 94.27 |
| N17945620 | 108.03 | 121.85 | 88.65 |
| N17945638 | 135.74 | 156.1 | 86.96 |
| N17949926 | 105.75 | 28.1 | 376.33 |
| N17951886 | 90.94 | 95.33 | 95.39 |
| N17952083 | 90.94 | 95.33 | 95.39 |
| N17952240 | 57.83 | 57.83 | 100 |
| N17952454 | 57.83 | 57.83 | 100 |
| N17993666 | 27.85 | 39.380000000000003 | 70.709999999999994 |
| N17993673 | 27.85 | 39.380000000000003 | 70.709999999999994 |
| N18003291 | 27.85 | 39.380000000000003 | 70.709999999999994 |
| N18003293 | 27.85 | 39.380000000000003 | 70.709999999999994 |
| N18003321 | 27.85 | 39.380000000000003 | 70.709999999999994 |
| N18003323 | 27.85 | 39.380000000000003 | 70.709999999999994 |
| N18003351 | 27.85 | 39.380000000000003 | 70.709999999999994 |
| N18003353 | 27.85 | 39.380000000000003 | 70.709999999999994 |
| N18003381 | 27.85 | 39.380000000000003 | 70.709999999999994 |
| N18003383 | 27.85 | 39.380000000000003 | 70.709999999999994 |
| N18003411 | 27.85 | 39.380000000000003 | 70.709999999999994 |
| N18003413 | 27.85 | 39.380000000000003 | 70.709999999999994 |
| N18003441 | 27.85 | 39.380000000000003 | 70.709999999999994 |
| N18003443 | 27.85 | 39.380000000000003 | 70.709999999999994 |
| N18003471 | 27.85 | 39.380000000000003 | 70.709999999999994 |
| N18003473 | 27.85 | 39.380000000000003 | 70.709999999999994 |
| N18003582 | 27.85 | 39.380000000000003 | 70.709999999999994 |
| N18003584 | 27.85 | 39.380000000000003 | 70.709999999999994 |
| N18003596 | 27.85 | 39.380000000000003 | 70.709999999999994 |
| N18003598 | 27.85 | 39.380000000000003 | 70.709999999999994 |
| N18003610 | 27.85 | 39.380000000000003 | 70.709999999999994 |
| N18003612 | 27.85 | 39.380000000000003 | 70.709999999999994 |
| N18003624 | 27.85 | 39.380000000000003 | 70.709999999999994 |
| N18003626 | 27.85 | 39.380000000000003 | 70.709999999999994 |
| N18003638 | 27.85 | 39.380000000000003 | 70.709999999999994 |
| N18003640 | 27.85 | 39.380000000000003 | 70.709999999999994 |
| N18003687 | 27.85 | 39.380000000000003 | 70.709999999999994 |
| N18003702 | 27.85 | 39.380000000000003 | 70.709999999999994 |
| N18003717 | 27.85 | 39.380000000000003 | 70.709999999999994 |
| N18003912 | 27.85 | 39.380000000000003 | 70.709999999999994 |
| N18003919 | 27.85 | 39.380000000000003 | 70.709999999999994 |
| N18003926 | 590.80999999999995 | 582.99 | 101.34 |
| N18003933 | 27.85 | 39.380000000000003 | 70.709999999999994 |
| N18003940 | 27.85 | 39.380000000000003 | 70.709999999999994 |
| N18006466 | 27.84 | 39.369999999999997 | 70.709999999999994 |
| N18006486 | 27.84 | 39.369999999999997 | 70.709999999999994 |
| N18006501 | 27.84 | 39.369999999999997 | 70.709999999999994 |
| N18006516 | 27.84 | 39.369999999999997 | 70.709999999999994 |
| N18006531 | 27.85 | 39.380000000000003 | 70.709999999999994 |
| N18006546 | 27.85 | 39.380000000000003 | 70.709999999999994 |
| N18006561 | 27.85 | 39.380000000000003 | 70.709999999999994 |
| N18006576 | 27.85 | 39.380000000000003 | 70.709999999999994 |
| N18006591 | 27.85 | 39.380000000000003 | 70.709999999999994 |
| N18006606 | 27.85 | 39.380000000000003 | 70.709999999999994 |
| N18006621 | 27.85 | 39.380000000000003 | 70.709999999999994 |
| N18006636 | 27.85 | 39.380000000000003 | 70.709999999999994 |
| N18007328 | 27.85 | 39.380000000000003 | 70.709999999999994 |
| N18007335 | 27.85 | 39.380000000000003 | 70.709999999999994 |
| N18007342 | 27.85 | 39.380000000000003 | 70.709999999999994 |
| N18007349 | 27.85 | 39.380000000000003 | 70.709999999999994 |
| N18007356 | 27.85 | 39.380000000000003 | 70.709999999999994 |
| N18007363 | 27.85 | 39.380000000000003 | 70.709999999999994 |
| N18007370 | 27.85 | 39.380000000000003 | 70.709999999999994 |
| N18007377 | 27.85 | 39.380000000000003 | 70.709999999999994 |
| N18007379 | 27.85 | 39.380000000000003 | 70.709999999999994 |
| N18007386 | 27.85 | 39.380000000000003 | 70.709999999999994 |
| N18007393 | 27.85 | 39.380000000000003 | 70.709999999999994 |
| N18007400 | 27.85 | 39.380000000000003 | 70.709999999999994 |
| N19012212 | 194.13 | 194.43 | 99.85 |
| N19640540 | 96.93 | 9.3699999999999992 | 1034.44 |
| N19641300 | 96.93 | 9.3699999999999992 | 1034.44 |
| OSC0_AS_CLKIN | 235.46 | 272.92 | 86.27 |
| OSC2_CONT | 119.35 | 99.86 | 119.52 |
| OSC2_OUT | 69.14 | 71.180000000000007 | 97.14 |
| P12V | 3646.18 | 27423.34 | 13.3 |
| P12V_PCIE | 1939.91 | 3034.51 | 63.93 |
| P1V26_STBY_PG | 34537.129999999997 | 22837.5 | 151.22999999999999 |
| P1V53_STBY_PG | 2525.02 | 2755.64 | 91.63 |
| P1V8_STBY | 331.4 | 26231.13 | 1.26 |
| P1V8_STBY_EN | 288.29000000000002 | 329.85 | 87.4 |
| P1V8_STBY_LL_R | 346.32 | 419.34 | 82.59 |
| P1V8_STBY_MODE | 710.84 | 451.24 | 157.53 |
| P1V8_STBY_PG | 11554.38 | 9511.06 | 121.48 |
| P1V8_STBY_RF | 155.87 | 169.48 | 91.97 |
| P1V8_STBY_ROVP | 311.33999999999997 | 318.89999999999998 | 97.63 |
| P1V8_STBY_SNB | 81.819999999999993 | 82.02 | 99.76 |
| P1V8_STBY_TRIP | 140.19 | 164.17 | 85.39 |
| P1V8_STBY_VBST | 167.06 | 103.1 | 162.04 |
| P1V8_STBY_VBST_RC | 97 | 97 | 100 |
| P1V8_STBY_VDD | 185.26 | 187.42 | 98.85 |
| P1V8_STBY_VFB | 214.08 | 225.16 | 95.08 |
| P1V8_STBY_VFB_R | 95.18 | 57.5 | 165.53 |
| P1V8_STBY_VREG | 829.28 | 722.72 | 114.74 |
| P3V3_STBY_EN | 373.5 | 457.33 | 81.67 |
| P3V3_STBY_LL_R | 458.14 | 509.34 | 89.95 |
| P3V3_STBY_MODE | 251.27 | 283.85000000000002 | 88.52 |
| P3V3_STBY_PG | 2221.0500000000002 | 1653.74 | 134.30000000000001 |
| P3V3_STBY_RF | 167.34 | 179.48 | 93.23 |
| P3V3_STBY_ROVP | 345.62 | 383.88 | 90.03 |
| P3V3_STBY_SNB | 62.86 | 63.28 | 99.33 |
| P3V3_STBY_TRIP | 260.58 | 309.17 | 84.29 |
| P3V3_STBY_VBST | 183.99 | 38.1 | 482.92 |
| P3V3_STBY_VBST_RC | 92 | 92 | 100 |
| P3V3_STBY_VDD | 205.6 | 220.52 | 93.23 |
| P3V3_STBY_VFB | 203.34 | 167.34 | 121.52 |
| P3V3_STBY_VFB_R | 289.45999999999998 | 274.33999999999997 | 105.51 |
| P3V3_STBY_VREG | 811.9 | 641.48 | 126.57 |
| P5V_STBY | 615.37 | 16852.39 | 3.65 |
| P5V_STBY_CC | 1569.09 | 1100 | 142.63999999999999 |
| P5V_STBY_CC_R | 176.04 | 127.5 | 138.07 |
| P5V_STBY_EN_R | 262.61 | 266.77999999999997 | 98.44 |
| P5V_STBY_PG | 3402.81 | 2661.53 | 127.85 |
| P5V_STBY_SS | 99.68 | 102.1 | 97.63 |
| P5V_STBY_VBST | 134.18 | 166.91 | 80.39 |
| P5V_STBY_VBST_RR | 94.75 | 47.5 | 199.47 |
| P5V_STBY_VFB | 344.92 | 252.59 | 136.55000000000001 |
| P5V_STBY_VFB_R | 730.3 | 907.5 | 80.47 |
| P5V_STBY_VIN | 0 | 594.6 | 0 |
| P5V_STBY_VO | 140.37 | 146.91 | 95.55 |
| P5V_STBY_VRG5 | 193.31 | 182.1 | 106.16 |
| P5V_STBY__SNB | 137.13999999999999 | 143 | 95.9 |
| P5V_USB | 147.41999999999999 | 1801.97 | 8.18 |
| P5V_USB_BP1_F | 0 | 267.10000000000002 | 0 |
| PCIE_MATED#_A | 2596.1799999999998 | 2777.2 | 93.48 |
| PCIE_MATED#_B | 15418.58 | 11673.11 | 132.09 |
| PD_PERST_N | 62.19 | 25.46 | 244.28 |
| PD_USB2VRES | 685.12 | 757.87 | 90.4 |
| PD_ZQ | 219.39 | 240.45 | 91.24 |
| PECI0_R | 725.69 | 865.08 | 83.89 |
| PEER_1B_2B_HB | 5628.52 | 5576.05 | 100.94 |
| PEER_1B_2B_HB_R | 714.75 | 732.03 | 97.64 |
| PEER_TRAY_BMC | 592.86 | 658.05 | 90.09 |
| PEER_TRAY_R | 7138.51 | 6429.39 | 111.03 |
| PEX_8780_I2C_SMBUS_CFG_EN | 696.92 | 655.63 | 106.3 |
| PEX_8780_I2C_SMBUS_SEL | 718.94 | 738.89 | 97.3 |
| PEX_8780_MGMT_CFG_EN | 1526.04 | 1763.79 | 86.52 |
| PEX_8780_NT0_PORTSEL0 | 1890.26 | 1904.44 | 99.26 |
| PEX_8780_NT0_PORTSEL1 | 1301.48 | 1188.8900000000001 | 109.47 |
| PEX_8780_NT0_PORTSEL2 | 643.54999999999995 | 651.89 | 98.72 |
| PEX_8780_NT1_PORTSEL0 | 2368.23 | 2630.66 | 90.02 |
| PEX_8780_NT1_PORTSEL1 | 2251.81 | 2623.18 | 85.84 |
| PEX_8780_NT1_PORTSEL2 | 2106.94 | 2473.1799999999998 | 85.19 |
| PEX_8780_SHPC_INT_N | 1363.24 | 1350.7 | 100.93 |
| PEX_8780_TESTMODE | 2203.7399999999998 | 2508.81 | 87.84 |
| PEX_NT0_PERST_N | 610.80999999999995 | 647.65 | 94.31 |
| PEX_NT1_PERST_N | 1260.31 | 1362.52 | 92.5 |
| PE_100M_CLK1_N | 119.62 | 120 | 99.68 |
| PE_100M_CLK1_P | 119.62 | 120 | 99.69 |
| PE_100M_CLK2_N | 3910.45 | 4359.03 | 89.71 |
| PE_100M_CLK2_P | 3909.64 | 4362.22 | 89.63 |
| PE_100M_CLK3_N | 1588.29 | 1792.05 | 88.63 |
| PE_100M_CLK3_P | 1588.29 | 1795.25 | 88.47 |
| PE_100M_CLK4_N | 1770.79 | 1848.39 | 95.8 |
| PE_100M_CLK4_P | 1771.96 | 1782.21 | 99.43 |
| PE_100M_R_CLK1_N | 2900.34 | 2803.93 | 103.44 |
| PE_100M_R_CLK1_P | 2900.05 | 2749.54 | 105.47 |
| PE_100M_R_CLK2_N | 107.12 | 107.5 | 99.65 |
| PE_100M_R_CLK2_P | 107.12 | 107.49 | 99.66 |
| PE_100M_R_CLK3_N | 107.12 | 107.49 | 99.66 |
| PE_100M_R_CLK3_P | 107.12 | 107.5 | 99.65 |
| PE_100M_R_CLK4_N | 107.7 | 109.55 | 98.31 |
| PE_100M_R_CLK4_P | 107.14 | 105.44 | 101.61 |
| PE_8780_I2C0_CLK | 3663.4 | 4720.29 | 77.61 |
| PE_8780_I2C0_SDA | 3592.51 | 4648.4799999999996 | 77.28 |
| PE_8780_I2C1_CLK | 1438.77 | 1433.18 | 100.39 |
| PE_8780_I2C1_SDA | 681.97 | 687.02 | 99.27 |
| PE_8780_I2C_ADDR | 2318.83 | 2658.81 | 87.21 |
| PE_9716_SW1_I2C0_CLK | 118.05 | 95.55 | 123.55 |
| PE_9716_SW1_I2C0_CLK_R | 722.13 | 751.8 | 96.05 |
| PE_9716_SW1_I2C0_SDA | 117.55 | 94.35 | 124.59 |
| PE_9716_SW1_I2C0_SDA_R | 513.73 | 544.32000000000005 | 94.38 |
| PE_9716_SW1_I2C1_CLK | 118.05 | 95.55 | 123.55 |
| PE_9716_SW1_I2C1_CLK_R | 782.63 | 775.53 | 100.92 |
| PE_9716_SW1_I2C1_SDA | 117.55 | 94.35 | 124.59 |
| PE_9716_SW1_I2C1_SDA_R | 683.34 | 652.38 | 104.75 |
| PE_9716_SW1_SHPC_INT | 12135.73 | 5430.75 | 223.46 |
| PE_9716_SW2_I2C0_CLK | 118.05 | 95.55 | 123.55 |
| PE_9716_SW2_I2C0_CLK_R | 645.66999999999996 | 759.86 | 84.97 |
| PE_9716_SW2_I2C0_SDA | 117.55 | 94.35 | 124.59 |
| PE_9716_SW2_I2C0_SDA_R | 608.1 | 631.12 | 96.35 |
| PE_9716_SW2_I2C1_CLK | 118.05 | 95.55 | 123.55 |
| PE_9716_SW2_I2C1_CLK_R | 1131.98 | 758.59 | 149.22 |
| PE_9716_SW2_I2C1_SDA | 117.55 | 94.35 | 124.59 |
| PE_9716_SW2_I2C1_SDA_R | 700.38 | 615.54 | 113.78 |
| PE_9716_SW2_SHPC_INT | 7985.09 | 5903.87 | 135.25 |
| PE_CLK100M_SW1_N | 7010.97 | 5447.51 | 128.69999999999999 |
| PE_CLK100M_SW1_P | 7012.02 | 5521.57 | 126.99 |
| PE_CLK100M_SW2_N | 3121.98 | 3484.13 | 89.61 |
| PE_CLK100M_SW2_P | 3121.98 | 3488.81 | 89.49 |
| PE_CLK100M_SW3_N | 5035.33 | 5533.43 | 91 |
| PE_CLK100M_SW3_P | 5035.33 | 5528.74 | 91.08 |
| PE_CLK_100M_SW1_R_N | 107.12 | 107.5 | 99.64 |
| PE_CLK_100M_SW1_R_P | 107.12 | 107.5 | 99.65 |
| PE_CLK_100M_SW2_R_N | 107.12 | 107.5 | 99.64 |
| PE_CLK_100M_SW2_R_P | 107.12 | 107.5 | 99.65 |
| PE_CLK_100M_SW3_R_N | 107.12 | 107.5 | 99.64 |
| PE_CLK_100M_SW3_R_P | 107.12 | 107.5 | 99.64 |
| PE_DN_RD1_C_N | 6761.7 | 6646.19 | 101.74 |
| PE_DN_RD1_C_P | 6763.3 | 6638.32 | 101.88 |
| PE_DN_RD2_C_N | 7007.75 | 6984.77 | 100.33 |
| PE_DN_RD2_C_P | 7009.2 | 6976.9 | 100.46 |
| PE_DN_RD3_C_N | 6913.48 | 7032.01 | 98.31 |
| PE_DN_RD3_C_P | 6915.1 | 7024.14 | 98.45 |
| PE_DN_RD4_C_N | 6865.19 | 7118.63 | 96.44 |
| PE_DN_RD4_C_P | 6866.39 | 7110.76 | 96.56 |
| PE_DN_RD5_C_N | 7008.13 | 7055.64 | 99.33 |
| PE_DN_RD5_C_P | 7007.21 | 7063.51 | 99.2 |
| PE_DN_RD6_C_N | 7061.24 | 7142.25 | 98.87 |
| PE_DN_RD6_C_P | 7060.54 | 7150.12 | 98.75 |
| PE_DN_RD7_C_N | 7121.23 | 7189.5 | 99.05 |
| PE_DN_RD7_C_P | 7120.08 | 7197.37 | 98.93 |
| PE_DN_RD8_C_N | 7168.8 | 7276.1 | 98.53 |
| PE_DN_RD8_C_P | 7167.1 | 7283.97 | 98.4 |
| PE_DN_RX24_C_N | 228.72 | 185.29 | 123.44 |
| PE_DN_RX24_C_P | 227.09 | 259.66000000000003 | 87.46 |
| PE_DN_RX24_N | 3906.3 | 4267.22 | 91.54 |
| PE_DN_RX24_P | 3907.76 | 4341.59 | 90.01 |
| PE_DN_RX25_C_N | 284.83999999999997 | 229.66 | 124.03 |
| PE_DN_RX25_C_P | 283.54000000000002 | 304.02999999999997 | 93.26 |
| PE_DN_RX25_N | 3827.83 | 4181.59 | 91.54 |
| PE_DN_RX25_P | 3829.58 | 4255.96 | 89.98 |
| PE_DN_RX26_C_N | 357.93 | 313.41000000000003 | 114.21 |
| PE_DN_RX26_C_P | 356.31 | 387.78 | 91.88 |
| PE_DN_RX26_N | 3748.74 | 4095.96 | 91.52 |
| PE_DN_RX26_P | 3746.75 | 4170.33 | 89.84 |
| PE_DN_RX27_C_N | 421.9 | 357.78 | 117.92 |
| PE_DN_RX27_C_P | 420.08 | 432.15 | 97.21 |
| PE_DN_RX27_N | 3665.91 | 4010.33 | 91.41 |
| PE_DN_RX27_P | 3667.06 | 4084.7 | 89.78 |
| PE_DN_RX28_C_N | 3020.02 | 3675.31 | 82.17 |
| PE_DN_RX28_C_P | 3018.95 | 3679.68 | 82.04 |
| PE_DN_RX28_N | 961.39 | 892.8 | 107.68 |
| PE_DN_RX28_P | 962.62 | 897.17 | 107.3 |
| PE_DN_RX29_C_N | 3107.88 | 3809.68 | 81.58 |
| PE_DN_RX29_C_P | 3106.41 | 3814.05 | 81.45 |
| PE_DN_RX29_N | 789.43 | 723.43 | 109.12 |
| PE_DN_RX29_P | 790.67 | 727.8 | 108.64 |
| PE_DN_RX30_C_N | 3397.36 | 4005.92 | 84.81 |
| PE_DN_RX30_C_P | 3395.78 | 4010.29 | 84.68 |
| PE_DN_RX30_N | 640.9 | 566.55999999999995 | 113.12 |
| PE_DN_RX30_P | 642.14 | 570.92999999999995 | 112.47 |
| PE_DN_RX31_C_N | 3539.27 | 4162.79 | 85.02 |
| PE_DN_RX31_C_P | 3537.8 | 4167.16 | 84.9 |
| PE_DN_RX31_N | 489.07 | 409.69 | 119.38 |
| PE_DN_RX31_P | 490.31 | 474.68 | 103.29 |
| PE_DN_RX72_C_N | 2222.21 | 2357.29 | 94.27 |
| PE_DN_RX72_C_P | 2220.59 | 2361.66 | 94.03 |
| PE_DN_RX72_N | 529.42999999999995 | 492.22 | 107.56 |
| PE_DN_RX72_P | 528.82000000000005 | 566.59 | 93.33 |
| PE_DN_RX73_C_N | 2212.27 | 2326.66 | 95.08 |
| PE_DN_RX73_C_P | 2210.64 | 2331.0300000000002 | 94.84 |
| PE_DN_RX73_N | 637.20000000000005 | 601.59 | 105.92 |
| PE_DN_RX73_P | 636.58000000000004 | 675.96 | 94.17 |
| PE_DN_RX74_C_N | 2186.0100000000002 | 2335.41 | 93.6 |
| PE_DN_RX74_C_P | 2184.39 | 2339.7800000000002 | 93.36 |
| PE_DN_RX74_N | 723.5 | 710.96 | 101.76 |
| PE_DN_RX74_P | 722.89 | 785.33 | 92.05 |
| PE_DN_RX75_C_N | 2176.06 | 2304.7800000000002 | 94.42 |
| PE_DN_RX75_C_P | 2174.44 | 2309.15 | 94.17 |
| PE_DN_RX75_N | 809.81 | 820.33 | 98.72 |
| PE_DN_RX75_P | 809.2 | 894.7 | 90.44 |
| PE_DN_RX76_C_N | 521.6 | 482.81 | 108.04 |
| PE_DN_RX76_C_P | 519.91999999999996 | 557.17999999999995 | 93.31 |
| PE_DN_RX76_N | 3050.4 | 3342.3 | 91.27 |
| PE_DN_RX76_P | 3051.43 | 3346.67 | 91.18 |
| PE_DN_RX77_C_N | 449.47 | 397.18 | 113.17 |
| PE_DN_RX77_C_P | 447.85 | 471.55 | 94.97 |
| PE_DN_RX77_N | 3038.55 | 3302.93 | 92 |
| PE_DN_RX77_P | 3039.59 | 3307.3 | 91.91 |
| PE_DN_RX78_C_N | 391.42 | 350.92 | 111.54 |
| PE_DN_RX78_C_P | 390.04 | 425.29 | 91.71 |
| PE_DN_RX78_N | 3059.41 | 3263.56 | 93.74 |
| PE_DN_RX78_P | 3060.45 | 3267.93 | 93.65 |
| PE_DN_RX79_C_N | 314.58999999999997 | 265.29000000000002 | 118.58 |
| PE_DN_RX79_C_P | 312.95 | 339.66 | 92.14 |
| PE_DN_RX79_N | 3059.33 | 3224.19 | 94.89 |
| PE_DN_RX79_P | 3060.37 | 3228.56 | 94.79 |
| PE_DN_TX24_C_N | 897.81 | 974.11 | 92.17 |
| PE_DN_TX24_C_P | 898.21 | 1048.48 | 85.67 |
| PE_DN_TX24_N | 3249.22 | 3431.52 | 94.69 |
| PE_DN_TX24_P | 3247.76 | 3435.89 | 94.52 |
| PE_DN_TX25_C_N | 808.25 | 883.48 | 91.48 |
| PE_DN_TX25_C_P | 808.65 | 957.85 | 84.42 |
| PE_DN_TX25_N | 3338.94 | 3522.15 | 94.8 |
| PE_DN_TX25_P | 3337.61 | 3526.52 | 94.64 |
| PE_DN_TX26_C_N | 678.8 | 792.85 | 85.62 |
| PE_DN_TX26_C_P | 679.21 | 867.22 | 78.319999999999993 |
| PE_DN_TX26_N | 3369.66 | 3573.4 | 94.3 |
| PE_DN_TX26_P | 3368.38 | 3577.77 | 94.15 |
| PE_DN_TX27_C_N | 601.9 | 702.22 | 85.71 |
| PE_DN_TX27_C_P | 603.59 | 776.59 | 77.72 |
| PE_DN_TX27_N | 3458.93 | 3664.03 | 94.4 |
| PE_DN_TX27_P | 3457.59 | 3668.4 | 94.25 |
| PE_DN_TX28_C_N | 3197.22 | 3729.09 | 85.74 |
| PE_DN_TX28_C_P | 3197.66 | 3803.46 | 84.07 |
| PE_DN_TX28_N | 573.05999999999995 | 558.41999999999996 | 102.62 |
| PE_DN_TX28_P | 574.05999999999995 | 562.79 | 102 |
| PE_DN_TX29_C_N | 3381.07 | 3908.46 | 86.51 |
| PE_DN_TX29_C_P | 3382 | 3982.83 | 84.91 |
| PE_DN_TX29_N | 487.45 | 457.79 | 106.48 |
| PE_DN_TX29_P | 487.96 | 462.16 | 105.58 |
| PE_DN_TX30_C_N | 3527.54 | 4087.83 | 86.29 |
| PE_DN_TX30_C_P | 3528.51 | 4162.2 | 84.78 |
| PE_DN_TX30_N | 421.43 | 396.53 | 106.28 |
| PE_DN_TX30_P | 422.1 | 400.9 | 105.29 |
| PE_DN_TX31_C_N | 3698.22 | 4267.2 | 86.67 |
| PE_DN_TX31_C_P | 3699.17 | 4341.57 | 85.2 |
| PE_DN_TX31_N | 332.52 | 295.89999999999998 | 112.38 |
| PE_DN_TX31_P | 332.76 | 308.39 | 107.9 |
| PE_DN_TX72_C_N | 3562.57 | 2484.67 | 143.38 |
| PE_DN_TX72_C_P | 3560.7 | 2499.04 | 142.47999999999999 |
| PE_DN_TX72_N | 684.27 | 726.52 | 94.18 |
| PE_DN_TX72_P | 685.34 | 740.89 | 92.5 |
| PE_DN_TX73_C_N | 3312.56 | 2470.3000000000002 | 134.1 |
| PE_DN_TX73_C_P | 3313.89 | 2484.67 | 133.37 |
| PE_DN_TX73_N | 762.65 | 812.15 | 93.9 |
| PE_DN_TX73_P | 763.72 | 826.52 | 92.4 |
| PE_DN_TX74_C_N | 3070.37 | 2460.9299999999998 | 124.76 |
| PE_DN_TX74_C_P | 3070.71 | 2475.3000000000002 | 124.05 |
| PE_DN_TX74_N | 793.67 | 863.4 | 91.92 |
| PE_DN_TX74_P | 794.73 | 877.77 | 90.54 |
| PE_DN_TX75_C_N | 2727.54 | 2416.56 | 112.87 |
| PE_DN_TX75_C_P | 2725.86 | 2480.9299999999998 | 109.87 |
| PE_DN_TX75_N | 839.42 | 919.03 | 91.34 |
| PE_DN_TX75_P | 840.52 | 983.4 | 85.47 |
| PE_DN_TX76_C_N | 373.59 | 369.69 | 101.05 |
| PE_DN_TX76_C_P | 374.47 | 374.06 | 100.11 |
| PE_DN_TX76_N | 2635.12 | 2296.5 | 114.74 |
| PE_DN_TX76_P | 2635.67 | 2292.13 | 114.99 |
| PE_DN_TX77_C_N | 445.97 | 460.32 | 96.88 |
| PE_DN_TX77_C_P | 447.54 | 464.69 | 96.31 |
| PE_DN_TX77_N | 2634.07 | 2205.87 | 119.41 |
| PE_DN_TX77_P | 2635.04 | 2201.5 | 119.69 |
| PE_DN_TX78_C_N | 515.82000000000005 | 550.95000000000005 | 93.62 |
| PE_DN_TX78_C_P | 516.83000000000004 | 555.32000000000005 | 93.07 |
| PE_DN_TX78_N | 2651.49 | 2154.61 | 123.06 |
| PE_DN_TX78_P | 2652.46 | 2150.2399999999998 | 123.36 |
| PE_DN_TX79_C_N | 591.42999999999995 | 641.58000000000004 | 92.18 |
| PE_DN_TX79_C_P | 592.53 | 645.95000000000005 | 91.73 |
| PE_DN_TX79_N | 2635.14 | 2063.98 | 127.67 |
| PE_DN_TX79_P | 2636.1 | 2059.61 | 127.99 |
| PE_RD3_RX1_N | 6420.68 | 6923.73 | 92.73 |
| PE_RD3_RX1_P | 6420.05 | 6994.6 | 91.79 |
| PE_RD3_RX2_N | 6393.25 | 7010.34 | 91.2 |
| PE_RD3_RX2_P | 6392.81 | 7081.21 | 90.28 |
| PE_RD3_RX3_N | 6396.57 | 7057.59 | 90.63 |
| PE_RD3_RX3_P | 6395.89 | 7128.45 | 89.72 |
| PE_RD3_RX4_N | 6405.39 | 7144.19 | 89.66 |
| PE_RD3_RX4_P | 6404.64 | 7215.06 | 88.77 |
| PE_RD3_TX1_C_N | 5931.41 | 6541.63 | 90.67 |
| PE_RD3_TX1_C_P | 5929.51 | 6612.5 | 89.67 |
| PE_RD3_TX1_N | 187.08 | 179 | 104.51 |
| PE_RD3_TX1_P | 187.06 | 179.01 | 104.5 |
| PE_RD3_TX2_C_N | 5926.77 | 6628.24 | 89.42 |
| PE_RD3_TX2_C_P | 5924.85 | 6699.11 | 88.44 |
| PE_RD3_TX2_N | 187.08 | 179 | 104.51 |
| PE_RD3_TX2_P | 187.07 | 179 | 104.51 |
| PE_RD3_TX3_C_N | 5931.02 | 6675.49 | 88.85 |
| PE_RD3_TX3_C_P | 5929.15 | 6746.36 | 87.89 |
| PE_RD3_TX3_N | 187.07 | 179 | 104.51 |
| PE_RD3_TX3_P | 187.07 | 179.01 | 104.5 |
| PE_RD3_TX4_C_N | 5935.07 | 6762.09 | 87.77 |
| PE_RD3_TX4_C_P | 5933.16 | 6832.96 | 86.83 |
| PE_RD3_TX4_N | 187.08 | 179 | 104.51 |
| PE_RD3_TX4_P | 187.07 | 179 | 104.51 |
| PE_RD_RX1_N | 7316.89 | 6792.07 | 107.73 |
| PE_RD_RX1_P | 7316.02 | 6784.19 | 107.84 |
| PE_RD_RX2_N | 7375.3 | 7004.67 | 105.29 |
| PE_RD_RX2_P | 7374.45 | 6996.79 | 105.4 |
| PE_RD_RX3_N | 7346.65 | 7051.91 | 104.18 |
| PE_RD_RX3_P | 7345.86 | 7044.04 | 104.28 |
| PE_RD_RX4_N | 7299.13 | 7138.52 | 102.25 |
| PE_RD_RX4_P | 7297.18 | 7130.65 | 102.34 |
| PE_RD_TX1_N | 187.07 | 179 | 104.51 |
| PE_RD_TX1_P | 187.07 | 179.01 | 104.5 |
| PE_RD_TX2_N | 187.07 | 179 | 104.51 |
| PE_RD_TX2_P | 187.07 | 179.01 | 104.5 |
| PE_RD_TX3_N | 187.07 | 179 | 104.51 |
| PE_RD_TX3_P | 187.08 | 179 | 104.51 |
| PE_RD_TX4_N | 187.07 | 179 | 104.51 |
| PE_RD_TX4_P | 187.07 | 179.01 | 104.5 |
| PE_RX1_DR10_N | 9415.01 | 10707.89 | 87.93 |
| PE_RX1_DR10_P | 9416.23 | 10715.76 | 87.87 |
| PE_RX1_DR11_N | 7976.88 | 8377.19 | 95.22 |
| PE_RX1_DR11_P | 7975.43 | 8448.0499999999993 | 94.41 |
| PE_RX1_DR12_N | 14003.36 | 11947.23 | 117.21 |
| PE_RX1_DR12_P | 14005.22 | 11876.36 | 117.93 |
| PE_RX1_DR13_N | 15622.93 | 14214.96 | 109.9 |
| PE_RX1_DR13_P | 15624.72 | 14144.09 | 110.47 |
| PE_RX1_DR14_N | 16045.87 | 14876.37 | 107.86 |
| PE_RX1_DR14_P | 16047.48 | 14805.51 | 108.39 |
| PE_RX1_DR1_N | 8991.4699999999993 | 10156.709999999999 | 88.53 |
| PE_RX1_DR1_P | 8990.02 | 10227.57 | 87.9 |
| PE_RX1_DR4_N | 6736.05 | 7684.23 | 87.66 |
| PE_RX1_DR4_P | 6735.71 | 7692.1 | 87.57 |
| PE_RX1_DR5_N | 7064.28 | 7311.75 | 96.62 |
| PE_RX1_DR5_P | 7065.55 | 7319.63 | 96.53 |
| PE_RX1_DR6_N | 8099.56 | 8723.64 | 92.85 |
| PE_RX1_DR6_P | 8098.11 | 8794.51 | 92.08 |
| PE_RX1_DR7_N | 7915.21 | 7459.02 | 106.12 |
| PE_RX1_DR7_P | 7913.79 | 7471.68 | 105.92 |
| PE_RX1_DR8_N | 14435.54 | 12608.65 | 114.49 |
| PE_RX1_DR8_P | 14437.34 | 12537.78 | 115.15 |
| PE_RX1_DR9_N | 14967.04 | 13553.53 | 110.43 |
| PE_RX1_DR9_P | 14968.79 | 13482.66 | 111.02 |
| PE_RX1_RD2_N | 7831.47 | 7936.25 | 98.68 |
| PE_RX1_RD2_P | 7830.02 | 8007.12 | 97.79 |
| PE_RX2_DR10_N | 9539.39 | 10873.24 | 87.73 |
| PE_RX2_DR10_P | 9540.6200000000008 | 10881.11 | 87.68 |
| PE_RX2_DR11_N | 8021.84 | 8463.7999999999993 | 94.78 |
| PE_RX2_DR11_P | 8020.39 | 8534.67 | 93.97 |
| PE_RX2_DR12_N | 13929.4 | 11781.88 | 118.23 |
| PE_RX2_DR12_P | 13931.29 | 11711.01 | 118.96 |
| PE_RX2_DR13_N | 15441.03 | 14049.6 | 109.9 |
| PE_RX2_DR13_P | 15442.8 | 13978.74 | 110.47 |
| PE_RX2_DR14_N | 15896.87 | 14711.02 | 108.06 |
| PE_RX2_DR14_P | 15898.46 | 14640.15 | 108.59 |
| PE_RX2_DR1_N | 9055.36 | 10243.32 | 88.4 |
| PE_RX2_DR1_P | 9053.91 | 10314.19 | 87.78 |
| PE_RX2_DR4_N | 6654.71 | 7518.87 | 88.51 |
| PE_RX2_DR4_P | 6654.27 | 7526.75 | 88.41 |
| PE_RX2_DR5_N | 7048.76 | 7398.37 | 95.27 |
| PE_RX2_DR5_P | 7049.92 | 7406.24 | 95.19 |
| PE_RX2_DR6_N | 8136.2 | 8810.26 | 92.35 |
| PE_RX2_DR6_P | 8134.75 | 8881.1200000000008 | 91.6 |
| PE_RX2_DR7_N | 7888.11 | 7487.43 | 105.35 |
| PE_RX2_DR7_P | 7886.68 | 7558.3 | 104.34 |
| PE_RX2_DR8_N | 14331.46 | 12443.29 | 115.17 |
| PE_RX2_DR8_P | 14333.32 | 12372.43 | 115.85 |
| PE_RX2_DR9_N | 14832.98 | 13388.17 | 110.79 |
| PE_RX2_DR9_P | 14834.69 | 13317.31 | 111.39 |
| PE_RX2_RD2_N | 7848.75 | 8022.86 | 97.83 |
| PE_RX2_RD2_P | 7847.3 | 8093.73 | 96.96 |
| PE_RX3_DR10_N | 9683.2999999999993 | 11038.6 | 87.72 |
| PE_RX3_DR10_P | 9684.84 | 11046.47 | 87.67 |
| PE_RX3_DR11_N | 8062.99 | 8550.41 | 94.3 |
| PE_RX3_DR11_P | 8061.54 | 8621.2800000000007 | 93.51 |
| PE_RX3_DR12_N | 13864.99 | 11616.52 | 119.36 |
| PE_RX3_DR12_P | 13864.95 | 11545.66 | 120.09 |
| PE_RX3_DR13_N | 15269.04 | 13884.25 | 109.97 |
| PE_RX3_DR13_P | 15270.77 | 13813.38 | 110.55 |
| PE_RX3_DR14_N | 15748.29 | 14545.66 | 108.27 |
| PE_RX3_DR14_P | 15749.87 | 14474.8 | 108.81 |
| PE_RX3_DR1_N | 9119.0400000000009 | 10329.93 | 88.28 |
| PE_RX3_DR1_P | 9117.61 | 10400.799999999999 | 87.66 |
| PE_RX3_DR4_N | 6554.12 | 6663.89 | 98.35 |
| PE_RX3_DR4_P | 6553.7 | 6656.01 | 98.46 |
| PE_RX3_DR5_N | 7108.45 | 7445.61 | 95.47 |
| PE_RX3_DR5_P | 7109.85 | 7453.49 | 95.39 |
| PE_RX3_DR6_N | 8171.84 | 8896.8700000000008 | 91.85 |
| PE_RX3_DR6_P | 8170.39 | 8967.74 | 91.11 |
| PE_RX3_DR7_N | 7860.95 | 7574.05 | 103.79 |
| PE_RX3_DR7_P | 7859.53 | 7644.91 | 102.81 |
| PE_RX3_DR8_N | 14221.65 | 12277.94 | 115.83 |
| PE_RX3_DR8_P | 14223.51 | 12207.07 | 116.52 |
| PE_RX3_DR9_N | 14693.12 | 13033.84 | 112.73 |
| PE_RX3_DR9_P | 14694.87 | 12962.98 | 113.36 |
| PE_RX3_RD2_N | 7874.82 | 8109.48 | 97.11 |
| PE_RX3_RD2_P | 7873.36 | 8180.35 | 96.25 |
| PE_RX4_DR10_N | 9827.5300000000007 | 11203.95 | 87.71 |
| PE_RX4_DR10_P | 9829.1200000000008 | 11211.82 | 87.67 |
| PE_RX4_DR11_N | 8064.02 | 8637.0300000000007 | 93.37 |
| PE_RX4_DR11_P | 8062.57 | 8707.89 | 92.59 |
| PE_RX4_DR12_N | 13775.3 | 11451.17 | 120.3 |
| PE_RX4_DR12_P | 13777.19 | 11380.3 | 121.06 |
| PE_RX4_DR13_N | 15109.6 | 13718.88 | 110.14 |
| PE_RX4_DR13_P | 15111.37 | 13648.02 | 110.72 |
| PE_RX4_DR14_N | 15602.13 | 14380.31 | 108.5 |
| PE_RX4_DR14_P | 15603.69 | 14309.44 | 109.04 |
| PE_RX4_DR1_N | 9203.7999999999993 | 10416.549999999999 | 88.36 |
| PE_RX4_DR1_P | 9201.89 | 10487.41 | 87.74 |
| PE_RX4_DR4_N | 6476 | 6750.5 | 95.93 |
| PE_RX4_DR4_P | 6475.53 | 6742.63 | 96.04 |
| PE_RX4_DR5_N | 7132.82 | 7532.22 | 94.7 |
| PE_RX4_DR5_P | 7134.17 | 7540.09 | 94.62 |
| PE_RX4_DR6_N | 8224.6299999999992 | 8983.49 | 91.55 |
| PE_RX4_DR6_P | 8223.18 | 9054.35 | 90.82 |
| PE_RX4_DR7_N | 7832.52 | 7849.64 | 99.78 |
| PE_RX4_DR7_P | 7831.08 | 7920.5 | 98.87 |
| PE_RX4_DR8_N | 14110.88 | 12112.58 | 116.5 |
| PE_RX4_DR8_P | 14112.75 | 12041.72 | 117.2 |
| PE_RX4_DR9_N | 14549.75 | 12868.49 | 113.06 |
| PE_RX4_DR9_P | 14551.48 | 12797.62 | 113.7 |
| PE_RX4_RD2_N | 7918.97 | 8196.08 | 96.62 |
| PE_RX4_RD2_P | 7917.52 | 8266.9500000000007 | 95.77 |
| PE_TX1_DR10_C_N | 8929.7199999999993 | 10325.790000000001 | 86.48 |
| PE_TX1_DR10_C_P | 8928.7099999999991 | 10333.66 | 86.4 |
| PE_TX1_DR10_N | 187.07 | 179.01 | 104.5 |
| PE_TX1_DR10_P | 187.07 | 179 | 104.51 |
| PE_TX1_DR11_C_N | 7527.86 | 7995.09 | 94.16 |
| PE_TX1_DR11_C_P | 7527.98 | 8065.96 | 93.33 |
| PE_TX1_DR11_N | 187.08 | 179.01 | 104.51 |
| PE_TX1_DR11_P | 187.06 | 179.01 | 104.5 |
| PE_TX1_DR12_C_N | 13851.29 | 11801.31 | 117.37 |
| PE_TX1_DR12_C_P | 13851.4 | 11730.44 | 118.08 |
| PE_TX1_DR12_N | 187.05 | 179.04 | 104.48 |
| PE_TX1_DR12_P | 187.09 | 179.04 | 104.5 |
| PE_TX1_DR13_C_N | 15434.25 | 14069.07 | 109.7 |
| PE_TX1_DR13_C_P | 15434.05 | 13998.2 | 110.26 |
| PE_TX1_DR13_N | 187.07 | 179 | 104.51 |
| PE_TX1_DR13_P | 187.07 | 179.01 | 104.5 |
| PE_TX1_DR14_C_N | 15898.83 | 14856.47 | 107.02 |
| PE_TX1_DR14_C_P | 15898.68 | 14785.6 | 107.53 |
| PE_TX1_DR14_N | 187.07 | 179 | 104.51 |
| PE_TX1_DR14_P | 187.07 | 179.01 | 104.5 |
| PE_TX1_DR1_C_N | 8673.99 | 9774.6 | 88.74 |
| PE_TX1_DR1_C_P | 8674.51 | 9845.4699999999993 | 88.11 |
| PE_TX1_DR1_N | 187.07 | 179 | 104.51 |
| PE_TX1_DR1_P | 187.08 | 179 | 104.51 |
| PE_TX1_DR4_C_N | 6451.76 | 7428.06 | 86.86 |
| PE_TX1_DR4_C_P | 6451.4 | 7435.93 | 86.76 |
| PE_TX1_DR4_N | 187.1 | 179.05 | 104.49 |
| PE_TX1_DR4_P | 187.05 | 179.05 | 104.47 |
| PE_TX1_DR5_N | 187.08 | 179 | 104.51 |
| PE_TX1_DR5_P | 187.07 | 179 | 104.51 |
| PE_TX1_DR6_C_N | 7626.71 | 8341.5400000000009 | 91.43 |
| PE_TX1_DR6_C_P | 7626.83 | 8412.41 | 90.66 |
| PE_TX1_DR6_N | 187.08 | 179 | 104.51 |
| PE_TX1_DR6_P | 187.07 | 179 | 104.51 |
| PE_TX1_DR7_C_N | 7419.42 | 7202.91 | 103.01 |
| PE_TX1_DR7_C_P | 7419.58 | 7210.78 | 102.9 |
| PE_TX1_DR7_N | 187.08 | 179 | 104.51 |
| PE_TX1_DR7_P | 187.07 | 179 | 104.51 |
| PE_TX1_DR8_C_N | 14286.41 | 12462.75 | 114.63 |
| PE_TX1_DR8_C_P | 14286.6 | 12391.88 | 115.29 |
| PE_TX1_DR8_N | 187.06 | 179.01 | 104.5 |
| PE_TX1_DR8_P | 187.08 | 179.02 | 104.5 |
| PE_TX1_DR9_C_N | 14787.31 | 13407.65 | 110.29 |
| PE_TX1_DR9_C_P | 14787.25 | 13336.78 | 110.88 |
| PE_TX1_DR9_N | 187.08 | 179 | 104.51 |
| PE_TX1_DR9_P | 187.07 | 179 | 104.51 |
| PE_TX1_RD2_C_N | 7437.12 | 7554.14 | 98.45 |
| PE_TX1_RD2_C_P | 7437.24 | 7625.01 | 97.54 |
| PE_TX1_RD2_N | 187.07 | 179.01 | 104.5 |
| PE_TX1_RD2_P | 187.07 | 179 | 104.51 |
| PE_TX2_DR10_C_N | 9055.39 | 10491.14 | 86.31 |
| PE_TX2_DR10_C_P | 9053.76 | 10499.01 | 86.23 |
| PE_TX2_DR10_N | 187.08 | 179 | 104.51 |
| PE_TX2_DR10_P | 187.07 | 179 | 104.51 |
| PE_TX2_DR11_C_N | 7553.79 | 8081.7 | 93.47 |
| PE_TX2_DR11_C_P | 7553.91 | 8152.57 | 92.66 |
| PE_TX2_DR11_N | 187.08 | 179 | 104.51 |
| PE_TX2_DR11_P | 187.06 | 179.01 | 104.5 |
| PE_TX2_DR12_C_N | 13740.08 | 11635.96 | 118.08 |
| PE_TX2_DR12_C_P | 13740.4 | 11565.09 | 118.81 |
| PE_TX2_DR12_N | 187.06 | 179.03 | 104.48 |
| PE_TX2_DR12_P | 187.09 | 179.04 | 104.49 |
| PE_TX2_DR13_C_N | 15260.11 | 13903.72 | 109.76 |
| PE_TX2_DR13_C_P | 15259.88 | 13832.85 | 110.32 |
| PE_TX2_DR13_N | 187.08 | 179 | 104.51 |
| PE_TX2_DR13_P | 187.07 | 179 | 104.51 |
| PE_TX2_DR14_C_N | 15739.09 | 14691.12 | 107.13 |
| PE_TX2_DR14_C_P | 15738.92 | 14620.25 | 107.65 |
| PE_TX2_DR14_N | 187.08 | 179 | 104.51 |
| PE_TX2_DR14_P | 187.07 | 179 | 104.51 |
| PE_TX2_DR1_C_N | 8674.86 | 9861.2199999999993 | 87.97 |
| PE_TX2_DR1_C_P | 8675.3700000000008 | 9932.09 | 87.35 |
| PE_TX2_DR1_N | 187.07 | 179 | 104.51 |
| PE_TX2_DR1_P | 187.07 | 179.01 | 104.5 |
| PE_TX2_DR4_C_N | 6356.01 | 7262.69 | 87.52 |
| PE_TX2_DR4_C_P | 6356.03 | 7270.56 | 87.42 |
| PE_TX2_DR4_N | 187.11 | 179.07 | 104.49 |
| PE_TX2_DR4_P | 187.04 | 179.07 | 104.45 |
| PE_TX2_DR5_N | 187.08 | 179 | 104.51 |
| PE_TX2_DR5_P | 187.07 | 179 | 104.51 |
| PE_TX2_DR6_C_N | 7653.77 | 8428.16 | 90.81 |
| PE_TX2_DR6_C_P | 7653.88 | 8499.0300000000007 | 90.06 |
| PE_TX2_DR6_N | 187.08 | 179.01 | 104.51 |
| PE_TX2_DR6_P | 187.06 | 179.01 | 104.5 |
| PE_TX2_DR7_C_N | 7401.87 | 7116.29 | 104.01 |
| PE_TX2_DR7_C_P | 7402.05 | 7176.2 | 103.15 |
| PE_TX2_DR7_N | 187.08 | 179 | 104.51 |
| PE_TX2_DR7_P | 187.07 | 179 | 104.51 |
| PE_TX2_DR8_C_N | 14179.03 | 12297.38 | 115.3 |
| PE_TX2_DR8_C_P | 14179.15 | 12226.51 | 115.97 |
| PE_TX2_DR8_N | 187.06 | 179.03 | 104.48 |
| PE_TX2_DR8_P | 187.09 | 179.03 | 104.5 |
| PE_TX2_DR9_C_N | 14647.28 | 13242.29 | 110.61 |
| PE_TX2_DR9_C_P | 14647.22 | 13171.42 | 111.2 |
| PE_TX2_DR9_N | 187.07 | 179 | 104.51 |
| PE_TX2_DR9_P | 187.07 | 179.01 | 104.5 |
| PE_TX2_RD2_C_N | 7455.45 | 7640.77 | 97.57 |
| PE_TX2_RD2_C_P | 7455.57 | 7711.64 | 96.68 |
| PE_TX2_RD2_N | 187.08 | 179.01 | 104.51 |
| PE_TX2_RD2_P | 187.06 | 179.01 | 104.5 |
| PE_TX3_DR10_C_N | 9171.61 | 10656.5 | 86.07 |
| PE_TX3_DR10_C_P | 9169.9599999999991 | 10664.37 | 85.99 |
| PE_TX3_DR10_N | 187.07 | 179.01 | 104.5 |
| PE_TX3_DR10_P | 187.07 | 179 | 104.51 |
| PE_TX3_DR11_C_N | 7572.19 | 8168.32 | 92.7 |
| PE_TX3_DR11_C_P | 7572.32 | 8239.19 | 91.91 |
| PE_TX3_DR11_N | 187.08 | 179.01 | 104.51 |
| PE_TX3_DR11_P | 187.06 | 179.01 | 104.5 |
| PE_TX3_DR12_C_N | 13632.01 | 11470.6 | 118.84 |
| PE_TX3_DR12_C_P | 13632.12 | 11399.73 | 119.58 |
| PE_TX3_DR12_N | 187.05 | 179.04 | 104.48 |
| PE_TX3_DR12_P | 187.09 | 179.04 | 104.5 |
| PE_TX3_DR13_C_N | 15073.62 | 13738.37 | 109.72 |
| PE_TX3_DR13_C_P | 15073.46 | 13667.5 | 110.29 |
| PE_TX3_DR13_N | 187.08 | 179 | 104.51 |
| PE_TX3_DR13_P | 187.07 | 179 | 104.51 |
| PE_TX3_DR14_C_N | 15577.44 | 14525.77 | 107.24 |
| PE_TX3_DR14_C_P | 15577.26 | 14454.9 | 107.76 |
| PE_TX3_DR14_N | 187.08 | 179 | 104.51 |
| PE_TX3_DR14_P | 187.07 | 179 | 104.51 |
| PE_TX3_DR1_C_N | 8691.51 | 9947.83 | 87.37 |
| PE_TX3_DR1_C_P | 8692.02 | 10018.700000000001 | 86.76 |
| PE_TX3_DR1_N | 187.07 | 179 | 104.51 |
| PE_TX3_DR1_P | 187.08 | 179 | 104.51 |
| PE_TX3_DR4_C_N | 6254.2 | 6517.99 | 95.95 |
| PE_TX3_DR4_C_P | 6254.41 | 6510.12 | 96.07 |
| PE_TX3_DR4_N | 187.07 | 179.02 | 104.5 |
| PE_TX3_DR4_P | 187.07 | 179.01 | 104.5 |
| PE_TX3_DR5_N | 187.07 | 179.01 | 104.5 |
| PE_TX3_DR5_P | 187.07 | 179 | 104.51 |
| PE_TX3_DR6_C_N | 7682.84 | 8514.77 | 90.23 |
| PE_TX3_DR6_C_P | 7682.94 | 8585.64 | 89.49 |
| PE_TX3_DR6_N | 187.08 | 179 | 104.51 |
| PE_TX3_DR6_P | 187.07 | 179 | 104.51 |
| PE_TX3_DR7_C_N | 7400.35 | 7191.94 | 102.9 |
| PE_TX3_DR7_C_P | 7400.52 | 7262.81 | 101.9 |
| PE_TX3_DR7_N | 187.08 | 179 | 104.51 |
| PE_TX3_DR7_P | 187.07 | 179 | 104.51 |
| PE_TX3_DR8_C_N | 14058.96 | 12132.02 | 115.88 |
| PE_TX3_DR8_C_P | 14059.07 | 12061.15 | 116.56 |
| PE_TX3_DR8_N | 187.05 | 179.04 | 104.48 |
| PE_TX3_DR8_P | 187.09 | 179.04 | 104.5 |
| PE_TX3_DR9_C_N | 14506.33 | 12887.95 | 112.56 |
| PE_TX3_DR9_C_P | 14506.32 | 12817.08 | 113.18 |
| PE_TX3_DR9_N | 187.06 | 179.01 | 104.5 |
| PE_TX3_DR9_P | 187.08 | 179.02 | 104.5 |
| PE_TX3_RD2_C_N | 7478.19 | 7727.38 | 96.78 |
| PE_TX3_RD2_C_P | 7478.3 | 7798.25 | 95.9 |
| PE_TX3_RD2_N | 187.08 | 179 | 104.51 |
| PE_TX3_RD2_P | 187.06 | 179.01 | 104.5 |
| PE_TX4_DR10_C_N | 9293.2099999999991 | 10821.84 | 85.87 |
| PE_TX4_DR10_C_P | 9291.57 | 10829.71 | 85.8 |
| PE_TX4_DR10_N | 187.08 | 179.01 | 104.51 |
| PE_TX4_DR10_P | 187.07 | 179.01 | 104.5 |
| PE_TX4_DR11_C_N | 7599.25 | 8254.93 | 92.06 |
| PE_TX4_DR11_C_P | 7599.37 | 8325.7999999999993 | 91.27 |
| PE_TX4_DR11_N | 187.08 | 179 | 104.51 |
| PE_TX4_DR11_P | 187.06 | 179.01 | 104.5 |
| PE_TX4_DR12_C_N | 13522.58 | 11305.25 | 119.61 |
| PE_TX4_DR12_C_P | 13522.68 | 11234.38 | 120.37 |
| PE_TX4_DR12_N | 187.05 | 179.04 | 104.48 |
| PE_TX4_DR12_P | 187.09 | 179.04 | 104.5 |
| PE_TX4_DR13_C_N | 14926.06 | 13573 | 109.97 |
| PE_TX4_DR13_C_P | 14926.06 | 13502.13 | 110.55 |
| PE_TX4_DR13_N | 187.08 | 179 | 104.51 |
| PE_TX4_DR13_P | 187.07 | 179 | 104.51 |
| PE_TX4_DR14_C_N | 15426.61 | 14360.41 | 107.42 |
| PE_TX4_DR14_C_P | 15426.42 | 14289.54 | 107.96 |
| PE_TX4_DR14_N | 187.07 | 179 | 104.51 |
| PE_TX4_DR14_P | 187.07 | 179.01 | 104.5 |
| PE_TX4_DR1_C_N | 8735.32 | 10034.450000000001 | 87.05 |
| PE_TX4_DR1_C_P | 8735.82 | 10105.32 | 86.45 |
| PE_TX4_DR1_N | 187.07 | 179 | 104.51 |
| PE_TX4_DR1_P | 187.07 | 179.01 | 104.5 |
| PE_TX4_DR4_C_N | 6175.08 | 6604.62 | 93.5 |
| PE_TX4_DR4_C_P | 6175.15 | 6596.75 | 93.61 |
| PE_TX4_DR4_N | 187.08 | 179 | 104.51 |
| PE_TX4_DR4_P | 187.07 | 179 | 104.51 |
| PE_TX4_DR5_N | 187.08 | 179 | 104.51 |
| PE_TX4_DR5_P | 187.07 | 179 | 104.51 |
| PE_TX4_DR6_C_N | 7717.1 | 8601.39 | 89.72 |
| PE_TX4_DR6_C_P | 7717.24 | 8672.26 | 88.99 |
| PE_TX4_DR6_N | 187.08 | 179.01 | 104.51 |
| PE_TX4_DR6_P | 187.06 | 179.01 | 104.5 |
| PE_TX4_DR7_C_N | 7398.32 | 7278.56 | 101.65 |
| PE_TX4_DR7_C_P | 7398.5 | 7349.43 | 100.67 |
| PE_TX4_DR7_N | 187.07 | 179 | 104.51 |
| PE_TX4_DR7_P | 187.07 | 179.01 | 104.5 |
| PE_TX4_DR8_C_N | 13959.1 | 11966.67 | 116.65 |
| PE_TX4_DR8_C_P | 13959.21 | 11895.8 | 117.35 |
| PE_TX4_DR8_N | 187.06 | 179.03 | 104.48 |
| PE_TX4_DR8_P | 187.09 | 179.04 | 104.49 |
| PE_TX4_DR9_C_N | 14363.15 | 12722.6 | 112.89 |
| PE_TX4_DR9_C_P | 14363.1 | 12651.73 | 113.53 |
| PE_TX4_DR9_N | 187.06 | 179.01 | 104.5 |
| PE_TX4_DR9_P | 187.08 | 179.01 | 104.51 |
| PE_TX4_RD2_C_N | 7469.34 | 7813.99 | 95.59 |
| PE_TX4_RD2_C_P | 7469.45 | 7884.86 | 94.73 |
| PE_TX4_RD2_N | 187.08 | 179.01 | 104.51 |
| PE_TX4_RD2_P | 187.06 | 179.01 | 104.5 |
| PE_UP_RX0_N | 4376.12 | 4446.37 | 98.42 |
| PE_UP_RX0_P | 4375.1099999999997 | 4460.1400000000003 | 98.09 |
| PE_UP_RX10_N | 2953.33 | 3058.57 | 96.56 |
| PE_UP_RX10_P | 2954.7 | 3072.35 | 96.17 |
| PE_UP_RX11_N | 2984.03 | 3168.81 | 94.17 |
| PE_UP_RX11_P | 2983.02 | 3182.59 | 93.73 |
| PE_UP_RX12_N | 2403.11 | 2753.45 | 87.28 |
| PE_UP_RX12_P | 2401.33 | 2767.23 | 86.78 |
| PE_UP_RX13_N | 2683.15 | 2916.84 | 91.99 |
| PE_UP_RX13_P | 2682.95 | 2981.8 | 89.98 |
| PE_UP_RX14_N | 2383.86 | 2743.61 | 86.89 |
| PE_UP_RX14_P | 2383.61 | 2757.39 | 86.44 |
| PE_UP_RX15_N | 2586.15 | 2907 | 88.96 |
| PE_UP_RX15_P | 2588.04 | 2971.96 | 87.08 |
| PE_UP_RX1_N | 4082.87 | 4531.01 | 90.11 |
| PE_UP_RX1_P | 4083.7 | 4595.9799999999996 | 88.85 |
| PE_UP_RX2_N | 4005.64 | 4279.04 | 93.61 |
| PE_UP_RX2_P | 4007.27 | 4292.82 | 93.35 |
| PE_UP_RX3_N | 3965.15 | 4389.28 | 90.34 |
| PE_UP_RX3_P | 3964.14 | 4403.0600000000004 | 90.03 |
| PE_UP_RX4_N | 3894.26 | 3790.85 | 102.73 |
| PE_UP_RX4_P | 3895.58 | 3855.82 | 101.03 |
| PE_UP_RX5_N | 3569.17 | 3901.09 | 91.49 |
| PE_UP_RX5_P | 3570 | 3966.06 | 90.01 |
| PE_UP_RX6_N | 3500.38 | 3649.12 | 95.92 |
| PE_UP_RX6_P | 3502.01 | 3662.9 | 95.61 |
| PE_UP_RX7_N | 3431.19 | 3759.36 | 91.27 |
| PE_UP_RX7_P | 3430.18 | 3773.14 | 90.91 |
| PE_UP_RX8_N | 3335.04 | 3200.3 | 104.21 |
| PE_UP_RX8_P | 3334.57 | 3265.26 | 102.12 |
| PE_UP_RX9_N | 3035.66 | 3310.54 | 91.7 |
| PE_UP_RX9_P | 3036.7 | 3375.5 | 89.96 |
| PE_UP_TX0_C_N | 3464.49 | 3746.7 | 92.47 |
| PE_UP_TX0_C_P | 3465.52 | 3821.07 | 90.7 |
| PE_UP_TX0_N | 417.95 | 410.13 | 101.91 |
| PE_UP_TX0_P | 417.96 | 360.49 | 115.94 |
| PE_UP_TX10_C_N | 2278.89 | 2307.4899999999998 | 98.76 |
| PE_UP_TX10_C_P | 2279.9299999999998 | 2381.86 | 95.72 |
| PE_UP_TX10_N | 368.48 | 358.72 | 102.72 |
| PE_UP_TX10_P | 368.28 | 309.07 | 119.16 |
| PE_UP_TX11_C_N | 2254.3000000000002 | 2198.12 | 102.56 |
| PE_UP_TX11_C_P | 2255.34 | 2272.4899999999998 | 99.25 |
| PE_UP_TX11_N | 596.01 | 531.37 | 112.16 |
| PE_UP_TX11_P | 595.13 | 470.78 | 126.41 |
| PE_UP_TX12_C_N | 1638.96 | 1757.45 | 93.26 |
| PE_UP_TX12_C_P | 1637.38 | 1761.82 | 92.94 |
| PE_UP_TX12_N | 594.47 | 556.67999999999995 | 106.79 |
| PE_UP_TX12_P | 595.99 | 566.09 | 105.28 |
| PE_UP_TX13_C_N | 1696.99 | 1866.82 | 90.9 |
| PE_UP_TX13_C_P | 1695.42 | 1871.19 | 90.61 |
| PE_UP_TX13_N | 663.77 | 636.29 | 104.32 |
| PE_UP_TX13_P | 663.22 | 645.70000000000005 | 102.71 |
| PE_UP_TX14_C_N | 1777.67 | 1976.19 | 89.95 |
| PE_UP_TX14_C_P | 1776.09 | 1980.56 | 89.68 |
| PE_UP_TX14_N | 464.52 | 379.46 | 122.42 |
| PE_UP_TX14_P | 464.9 | 429.11 | 108.34 |
| PE_UP_TX15_C_N | 1858.33 | 2085.56 | 89.1 |
| PE_UP_TX15_C_P | 1856.75 | 2089.9299999999998 | 88.84 |
| PE_UP_TX15_N | 460.64 | 407.71 | 112.98 |
| PE_UP_TX15_P | 460.81 | 417.12 | 110.47 |
| PE_UP_TX1_C_N | 3373.53 | 3637.33 | 92.75 |
| PE_UP_TX1_C_P | 3374.56 | 3711.7 | 90.92 |
| PE_UP_TX1_N | 725.23 | 489.74 | 148.09 |
| PE_UP_TX1_P | 723.45 | 440.1 | 164.38 |
| PE_UP_TX2_C_N | 3292.85 | 3527.96 | 93.34 |
| PE_UP_TX2_C_P | 3293.89 | 3602.33 | 91.44 |
| PE_UP_TX2_N | 368.48 | 358.72 | 102.72 |
| PE_UP_TX2_P | 368.28 | 309.07 | 119.16 |
| PE_UP_TX3_C_N | 3212.19 | 3418.59 | 93.96 |
| PE_UP_TX3_C_P | 3213.22 | 3492.96 | 91.99 |
| PE_UP_TX3_N | 596.20000000000005 | 531.37 | 112.2 |
| PE_UP_TX3_P | 594.27 | 470.78 | 126.23 |
| PE_UP_TX4_C_N | 2959.59 | 3116.78 | 94.96 |
| PE_UP_TX4_C_P | 2960.63 | 3191.15 | 92.78 |
| PE_UP_TX4_N | 417.91 | 410.13 | 101.9 |
| PE_UP_TX4_P | 418.82 | 360.49 | 116.18 |
| PE_UP_TX5_C_N | 2876.18 | 3007.41 | 95.64 |
| PE_UP_TX5_C_P | 2877.21 | 3081.78 | 93.36 |
| PE_UP_TX5_N | 720.55 | 489.74 | 147.13 |
| PE_UP_TX5_P | 720.06 | 440.1 | 163.61000000000001 |
| PE_UP_TX6_C_N | 2792.76 | 2898.04 | 96.37 |
| PE_UP_TX6_C_P | 2793.8 | 2972.41 | 93.99 |
| PE_UP_TX6_N | 368.48 | 358.72 | 102.72 |
| PE_UP_TX6_P | 368.28 | 309.07 | 119.16 |
| PE_UP_TX7_C_N | 2709.36 | 2788.67 | 97.16 |
| PE_UP_TX7_C_P | 2710.39 | 2863.04 | 94.67 |
| PE_UP_TX7_N | 596.45000000000005 | 531.37 | 112.25 |
| PE_UP_TX7_P | 595.53 | 470.78 | 126.5 |
| PE_UP_TX8_C_N | 2456.09 | 2526.23 | 97.22 |
| PE_UP_TX8_C_P | 2457.12 | 2600.6 | 94.48 |
| PE_UP_TX8_N | 418.04 | 410.14 | 101.93 |
| PE_UP_TX8_P | 417.71 | 360.49 | 115.87 |
| PE_UP_TX9_C_N | 2367.04 | 2416.86 | 97.94 |
| PE_UP_TX9_C_P | 2368.0700000000002 | 2491.23 | 95.06 |
| PE_UP_TX9_N | 728.47 | 489.75 | 148.74 |
| PE_UP_TX9_P | 727 | 440.1 | 165.19 |
| PGD_SW1_VCC_0V9 | 13107.59 | 8591.65 | 152.56 |
| PGD_SW1_VCC_0V9_R | 581.82000000000005 | 516.67999999999995 | 112.61 |
| PGD_SW2_VCC_0V9 | 2228.73 | 2716.75 | 82.04 |
| PGD_VCCA_0V9 | 1531.72 | 676.75 | 226.34 |
| PGD_VCC_0V9 | 8547.7800000000007 | 7895.4 | 108.26 |
| PORT0_GOOD_LED | 112.68 | 120 | 93.9 |
| PORT0_GOOD_LED_G | 146.38999999999999 | 120 | 121.99 |
| PORT0_GOOD_LED_R | 52.5 | 52.5 | 100 |
| PORT0_GOOD_LED_R_G | 63.32 | 6.25 | 1013.14 |
| PORT1_GOOD_LED | 62.5 | 62.5 | 100 |
| PORT1_GOOD_LED_G | 146.38999999999999 | 120 | 121.99 |
| PORT1_GOOD_LED_R | 46.04 | 47.5 | 96.92 |
| PORT1_GOOD_LED_R_G | 63.32 | 6.25 | 1013.14 |
| PORT2_GOOD_LED | 81.17 | 88.47 | 91.74 |
| PORT2_GOOD_LED_G | 180.61 | 185 | 97.63 |
| PORT2_GOOD_LED_R | 67.5 | 67.5 | 100 |
| PORT2_GOOD_LED_R_G | 172.54 | 165.22 | 104.43 |
| PORT3_GOOD_LED | 81.17 | 88.47 | 91.74 |
| PORT3_GOOD_LED_G | 180.61 | 185 | 97.63 |
| PORT3_GOOD_LED_R | 67.5 | 67.5 | 100 |
| PORT3_GOOD_LED_R_G | 172.54 | 165.22 | 104.43 |
| PRSNT_AND_1 | 85.11 | 99.4 | 85.62 |
| PRSNT_AND_2 | 139.91 | 125 | 111.93 |
| PRSNT_AND_3 | 85.11 | 99.4 | 85.62 |
| PRSNT_AND_4 | 178.68 | 137.5 | 129.94999999999999 |
| PRSNT_AND_5 | 117.43 | 99.4 | 118.14 |
| PRSNT_AND_6 | 178.68 | 137.5 | 129.94999999999999 |
| PU_BMC0_SCL13 | 785.14 | 932.24 | 84.22 |
| PU_BMC0_SDA13 | 710.83 | 829.24 | 85.72 |
| PU_IBMC_BT_HOLD_N | 216.34 | 42.59 | 507.95 |
| PWM_EXP_A | 4672.1099999999997 | 4530.0600000000004 | 103.14 |
| ROMA0 | 8680.83 | 4747.96 | 182.83 |
| ROMA1 | 497.22 | 554.89 | 89.61 |
| ROMA2 | 449.74 | 483.39 | 93.04 |
| ROMA3 | 921.46 | 895.88 | 102.86 |
| ROMA4 | 581.94000000000005 | 689.38 | 84.42 |
| ROMA5 | 551.82000000000005 | 617.88 | 89.31 |
| ROMA6 | 478.62 | 506.39 | 94.52 |
| ROMA7 | 431.9 | 434.89 | 99.31 |
| ROMA8 | 542.32000000000005 | 552.37 | 98.18 |
| ROMA9 | 495.9 | 480.87 | 103.13 |
| ROMA10 | 474.84 | 456.56 | 104 |
| ROMA11 | 438.38 | 465.06 | 94.26 |
| ROMA12 | 607.16999999999996 | 655.37 | 92.64 |
| ROMA13 | 521.67999999999995 | 528.04999999999995 | 98.79 |
| ROMA14 | 480.48 | 472.37 | 101.72 |
| ROMA15 | 482.09 | 505.06 | 95.45 |
| ROMA16 | 925.28 | 872.89 | 106 |
| ROMA17 | 937.9 | 887.38 | 105.69 |
| ROMA18 | 579.48 | 640.88 | 90.42 |
| ROMA19 | 606.85 | 663.87 | 91.41 |
| ROMA20 | 429.8 | 416.55 | 103.18 |
| ROMA21 | 496.04 | 489.38 | 101.36 |
| ROMA22 | 455.36 | 513.55999999999995 | 88.67 |
| ROMA23 | 940.67 | 941.86 | 99.87 |
| ROMD0 | 12553.15 | 11757.44 | 106.77 |
| ROMD1 | 12536.25 | 11765.94 | 106.55 |
| ROMD2 | 11388.64 | 11926.84 | 95.49 |
| ROMD3 | 462.37 | 530.4 | 87.17 |
| ROMD4 | 516.12 | 601.9 | 85.75 |
| ROMD5 | 599.91 | 706.39 | 84.93 |
| ROMD6 | 483.78 | 578.91 | 83.57 |
| ROMD7 | 590.07000000000005 | 723.39 | 81.569999999999993 |
| ROMD0_R | 230.71 | 69.099999999999994 | 333.88 |
| ROMD1_R | 205.86 | 75.91 | 271.19 |
| ROMD2_R | 353.96 | 361.77 | 97.84 |
| RST_BMC_DDR3_R_N | 108.31 | 68.28 | 158.62 |
| SAS_I2C_B_BUF_SCL | 2367.75 | 2109.44 | 112.25 |
| SAS_I2C_B_BUF_SCL_R | 203.42 | 205.77 | 98.86 |
| SAS_I2C_B_BUF_SDA | 2163.79 | 1987.94 | 108.85 |
| SAS_I2C_B_BUF_SDA_R | 220.39 | 207.73 | 106.09 |
| SAS_I2C_C_BUF_SCL | 2824.75 | 2733.14 | 103.35 |
| SAS_I2C_C_BUF_SCL_R | 205.89 | 201.75 | 102.05 |
| SAS_I2C_C_BUF_SDA | 2522.75 | 2555.34 | 98.72 |
| SAS_I2C_C_BUF_SDA_R | 210.04 | 211.76 | 99.19 |
| SHUTDOWN_RELEASE | 11094.25 | 8471.35 | 130.96 |
| SMB_MINISAS_A_ADR0 | 124.02 | 95.99 | 129.19999999999999 |
| SMB_MINISAS_A_ADR1 | 148.22 | 121.58 | 121.91 |
| SMB_MINISAS_A_ADR2 | 128.11000000000001 | 97.17 | 131.84 |
| SMB_MINISAS_A_SCL | 1217.46 | 1447.26 | 84.12 |
| SMB_MINISAS_A_SCL_BUF | 4879.26 | 5458.6 | 89.39 |
| SMB_MINISAS_A_SCL_R | 135.55000000000001 | 86.49 | 156.72 |
| SMB_MINISAS_A_SDA | 1791.66 | 1788.8 | 100.16 |
| SMB_MINISAS_A_SDA_BUF | 4866.46 | 5262.16 | 92.48 |
| SMB_MINISAS_A_SDA_R | 160.55000000000001 | 111.49 | 144 |
| SMB_MINISAS_B_SCL | 1675.48 | 1917.83 | 87.36 |
| SMB_MINISAS_B_SCL_BUF | 7385.66 | 4901.88 | 150.66999999999999 |
| SMB_MINISAS_B_SCL_R | 117.67 | 26.01 | 452.4 |
| SMB_MINISAS_B_SDA | 1870.87 | 2184.37 | 85.65 |
| SMB_MINISAS_B_SDA_BUF | 7192.22 | 4641.58 | 154.94999999999999 |
| SMB_MINISAS_B_SDA_R | 96.63 | 44.47 | 217.29 |
| SMB_MINISAS_C_SCL | 2367.29 | 2613.41 | 90.58 |
| SMB_MINISAS_C_SCL_BUF | 3221.43 | 3162.52 | 101.86 |
| SMB_MINISAS_C_SCL_R | 135.55000000000001 | 86.49 | 156.72 |
| SMB_MINISAS_C_SDA | 2872.63 | 2954.94 | 97.21 |
| SMB_MINISAS_C_SDA_BUF | 3361.28 | 3462.7 | 97.07 |
| SMB_MINISAS_C_SDA_R | 160.55000000000001 | 111.49 | 144 |
| SMB_MINISAS_D_SCL | 2840.96 | 3083.98 | 92.12 |
| SMB_MINISAS_D_SCL_BUF | 4001.01 | 3527.26 | 113.43 |
| SMB_MINISAS_D_SCL_R | 117.67 | 26.01 | 452.4 |
| SMB_MINISAS_D_SDA | 3080.23 | 3350.51 | 91.93 |
| SMB_MINISAS_D_SDA_BUF | 5397.81 | 3797.44 | 142.13999999999999 |
| SMB_MINISAS_D_SDA_R | 96.63 | 44.47 | 217.29 |
| STRAP_GEN1_COMPLIANCE | 2411.46 | 2815.7 | 85.64 |
| STRAP_GEN1_GEN2 | 1022.48 | 1165.67 | 87.72 |
| STRAP_HP_POLARITY_CTRL | 1260.45 | 1301.29 | 96.86 |
| STRAP_PLL_BYPASS | 1436.26 | 1436.92 | 99.95 |
| STRAP_PROBE_MODE | 1021.75 | 1080.03 | 94.6 |
| STRAP_SERDES_MODE_EN | 1134.56 | 1340.67 | 84.63 |
| STRAP_STN0_PORTCFG0 | 1229.69 | 1202.57 | 102.26 |
| STRAP_STN0_PORTCFG1 | 1843.32 | 1641.94 | 112.26 |
| STRAP_STN1_PORTCFG0 | 2026.86 | 2319.44 | 87.39 |
| STRAP_STN1_PORTCFG1 | 2061.5100000000002 | 2430.0700000000002 | 84.83 |
| STRAP_STN2_PORTCFG0 | 1197 | 1312.52 | 91.2 |
| STRAP_STN2_PORTCFG1 | 1397.35 | 1601.89 | 87.23 |
| STRAP_STN3_PORTCFG0 | 989.09 | 1208.18 | 81.87 |
| STRAP_STN3_PORTCFG1 | 892 | 1061.33 | 84.05 |
| STRAP_STN4_PORTCFG0 | 1476.33 | 1723.74 | 85.65 |
| STRAP_STN4_PORTCFG1 | 1067.08 | 1229.44 | 86.79 |
| STRAP_UPSTRM_PORTSEL0 | 1016.92 | 997.55 | 101.94 |
| STRAP_UPSTRM_PORTSEL1 | 2600.9899999999998 | 2515.6999999999998 | 103.39 |
| STRAP_UPSTRM_PORTSEL2 | 1130.8399999999999 | 1355.03 | 83.45 |
| SW1_I2C1_SCL_DR4_R | 97.12 | 98.33 | 98.77 |
| SW1_I2C1_SCL_PORT0_R | 97.12 | 98.33 | 98.77 |
| SW1_I2C1_SCL_PORT5_R | 97.12 | 98.33 | 98.77 |
| SW1_I2C1_SDA_DR4_R | 103.44 | 113.6 | 91.06 |
| SW1_I2C1_SDA_PORT0_R | 103.44 | 113.6 | 91.06 |
| SW1_I2C1_SDA_PORT5_R | 103.44 | 113.6 | 91.06 |
| SW1_REXT_A0 | 348.38 | 414.46 | 84.06 |
| SW1_REXT_A1 | 407.71 | 446.35 | 91.34 |
| SW1_REXT_A2 | 436.28 | 518.85 | 84.09 |
| SW1_REXT_A3 | 420.1 | 485.09 | 86.6 |
| SW1_REXT_B0 | 420.56 | 491.33 | 85.6 |
| SW1_REXT_B1 | 406.92 | 410.72 | 99.07 |
| SW1_REXT_B2 | 437.05 | 520.72 | 83.93 |
| SW1_REXT_B3 | 447.25 | 561.96 | 79.59 |
| SW1_REXT_CMU | 526.6 | 566.33000000000004 | 92.98 |
| SW1_SHPC_INT_DR3_R | 131.58000000000001 | 143.01 | 92.01 |
| SW1_SHPC_INT_DR5_R | 131.58000000000001 | 143.01 | 92.01 |
| SW1_SHPC_INT_R | 131.58000000000001 | 143.01 | 92.01 |
| SW1_VCC_0V9_EN | 257.37 | 218.24 | 117.93 |
| SW1_VCC_0V9_MODE | 63.07 | 2.1800000000000002 | 2893.33 |
| SW1_VCC_0V9_RF | 91.58 | 97.2 | 94.22 |
| SW1_VCC_0V9_TRIP | 206.98 | 270.68 | 76.47 |
| SW1_VCC_0V9_VDD | 240.42 | 232.62 | 103.36 |
| SW1_VCC_0V9_VREG | 181.13 | 183.31 | 98.81 |
| SW2_I2C1_SCL_DR3_R | 97.12 | 98.33 | 98.77 |
| SW2_I2C1_SDA_DR3_R | 103.44 | 113.6 | 91.06 |
| SW2_REXT_A0 | 392.51 | 403.84 | 97.19 |
| SW2_REXT_A1 | 475.9 | 534.45000000000005 | 89.04 |
| SW2_REXT_A2 | 426.96 | 496.35 | 86.02 |
| SW2_REXT_A3 | 366.85 | 462.59 | 79.3 |
| SW2_REXT_B0 | 452.59 | 493.21 | 91.76 |
| SW2_REXT_B1 | 444.93 | 486.32 | 91.49 |
| SW2_REXT_B2 | 427.73 | 498.22 | 85.85 |
| SW2_REXT_B3 | 440.27 | 539.46 | 81.61 |
| SW2_REXT_CMU | 394.38 | 405.71 | 97.21 |
| SW2_SHPC_INT_DR4_R | 131.58000000000001 | 143.01 | 92.01 |
| SW2_VCC_0V9_VDD | 237.5 | 232.62 | 102.1 |
| TEMP_1_A0 | 177.35 | 184.69 | 96.03 |
| TEMP_1_A1 | 185.13 | 204.14 | 90.69 |
| TEMP_1_SCL | 122.84 | 127.3 | 96.49 |
| TEMP_1_SDA | 129.05000000000001 | 156.69999999999999 | 82.36 |
| TEMP_2_A0 | 150.80000000000001 | 163.80000000000001 | 92.06 |
| TEMP_2_A1 | 146.65 | 149.4 | 98.16 |
| TEMP_2_A2 | 190.65 | 188.2 | 101.3 |
| TEMP_2_ALERT | 146.58000000000001 | 171.3 | 85.57 |
| TEMP_2_SCL | 155.19 | 159.4 | 97.36 |
| TEMP_2_SDA | 120.9 | 148.19999999999999 | 81.58 |
| TEMP_SENSOR_C | 370.2 | 339.53 | 109.03 |
| TEMP_SENSOR_DXN | 524.29 | 599.20000000000005 | 87.5 |
| TEMP_SENSOR_DXN_BJT | 333.92 | 366.89 | 91.01 |
| TEMP_SENSOR_DXP | 622 | 623.6 | 99.74 |
| TEMP_SENSOR_DXP_R | 327.72 | 379.25 | 86.41 |
| TPS74801_1V26_STBY_BIAS | 184.94 | 198.89 | 92.98 |
| TPS74801_1V26_STBY_EN | 266.27999999999997 | 276.37 | 96.35 |
| TPS74801_1V26_STBY_FB | 215.03 | 183.89 | 116.93 |
| TPS74801_1V26_STBY_OUT | 0 | 937.66 | 0 |
| TPS74801_1V26_STBY_SS | 142.22999999999999 | 106.25 | 133.86000000000001 |
| TPS74801_1V53_STBY_BIAS | 190.71 | 163.89 | 116.36 |
| TPS74801_1V53_STBY_EN | 230.34 | 198.89 | 115.81 |
| TPS74801_1V53_STBY_FB | 226.46 | 204.53 | 110.72 |
| TPS74801_1V53_STBY_OUT | 37.29 | 1343.37 | 2.78 |
| TPS74801_1V53_STBY_SS | 141.97 | 103.89 | 136.66 |
| TPS74801_P1V26_STBY_IN | 0 | 572.54999999999995 | 0 |
| TPS74801_P1V53_STBY_IN | 0 | 567.91 | 0 |
| TP_BMC0_LPC_LAD0 | 573.20000000000005 | 741.6 | 77.290000000000006 |
| TP_BMC0_LPC_LAD1 | 543.71 | 718.6 | 75.66 |
| TP_BMC0_LPC_LAD2 | 535.1 | 639.85 | 83.63 |
| TP_BMC0_LPC_LAD3 | 382.41 | 476.08 | 80.319999999999993 |
| TP_BMC0_TACH8 | 183.16 | 241.53 | 75.83 |
| TP_BMC_GPIOA6 | 287.87 | 354.73 | 81.150000000000006 |
| TP_BMC_GPIOA7 | 102.38 | 92.22 | 111.01 |
| TP_BMC_GPIOE0 | 59.05 | 75.819999999999993 | 77.88 |
| TP_BMC_GPIOE1 | 126.99 | 100.68 | 126.14 |
| TP_BMC_GPIOE2 | 194.97 | 218.07 | 89.41 |
| TP_BMC_GPIOE3 | 213.47 | 236.57 | 90.23 |
| TP_BMC_GPIOE4 | 67.66 | 94.86 | 71.319999999999993 |
| TP_BMC_GPIOE5 | 94.63 | 112.56 | 84.08 |
| TP_BMC_GPIOF0 | 129.51 | 113.88 | 113.72 |
| TP_BMC_GPIOF1 | 337.22 | 387.09 | 87.12 |
| TP_BMC_GPIOF2 | 352.62 | 374.09 | 94.26 |
| TP_BMC_GPIOF3 | 148.04 | 158.07 | 93.65 |
| TP_BMC_GPIOF4 | 220.03 | 278.58999999999997 | 78.98 |
| TP_BMC_GPIOF5 | 239.98 | 300.58999999999997 | 79.84 |
| TP_BMC_GPIOF6 | 73.239999999999995 | 80.83 | 90.61 |
| TP_BMC_GPIOF7 | 132 | 186.53 | 70.77 |
| TP_BMC_GPIOI0 | 490.58 | 616.59 | 79.56 |
| TP_BMC_GPIOJ4 | 144.24 | 133.47 | 108.07 |
| TP_BMC_GPIOJ5 | 148.99 | 90.54 | 164.56 |
| TP_BMC_GPIOJ6 | 231.74 | 163.63999999999999 | 141.62 |
| TP_BMC_GPIOJ7 | 78.930000000000007 | 99.18 | 79.58 |
| TP_BMC_GPIOL0 | 151.47 | 150.68 | 100.53 |
| TP_BMC_GPIOL1 | 67.83 | 32.97 | 205.72 |
| TP_BMC_GPIOL2 | 201.5 | 193.63 | 104.06 |
| TP_BMC_GPIOL3 | 267.08999999999997 | 257.17 | 103.86 |
| TP_BMC_GPIOL4 | 287.29000000000002 | 275.02999999999997 | 104.46 |
| TP_BMC_GPIOL5 | 258.27999999999997 | 263.67 | 97.95 |
| TP_BMC_GPIOL6 | 216.41 | 198.67 | 108.93 |
| TP_BMC_GPIOL7 | 84.34 | 105.47 | 79.97 |
| TP_BMC_GPIOM0 | 292.60000000000002 | 320.16000000000003 | 91.39 |
| TP_BMC_GPIOM1 | 195.19 | 185.17 | 105.41 |
| TP_BMC_GPIOM2 | 217.16 | 209.05 | 103.88 |
| TP_BMC_GPIOM3 | 108.01 | 75.14 | 143.74 |
| TP_BMC_GPIOM4 | 88.16 | 78.239999999999995 | 112.68 |
| TP_BMC_GPIOM5 | 192.03 | 185.55 | 103.49 |
| TP_BMC_GPIOM6 | 185.08 | 202.56 | 91.37 |
| TP_BMC_GPIOM7 | 57.83 | 69.06 | 83.74 |
| TP_BMC_GPIOO7 | 70.53 | 65.849999999999994 | 107.11 |
| TP_BMC_GPIOR1 | 202.68 | 202.41 | 100.13 |
| TP_BMC_GPIOR2 | 168.72 | 192.41 | 87.69 |
| TP_BMC_GPIOR3 | 138.38 | 163.61000000000001 | 84.58 |
| TP_BMC_GPIOR4 | 641.91 | 567.88 | 113.04 |
| TP_BMC_GPIOR5 | 1127.45 | 494.39 | 228.05 |
| TP_BMC_GPIOT7 | 170.19 | 134.69999999999999 | 126.35 |
| TP_BMC_GPIOU2 | 156.94 | 153.19999999999999 | 102.44 |
| TP_BMC_GPIOU3 | 60.21 | 21.8 | 276.18 |
| TP_BMC_GPIOV3 | 531.53 | 670.21 | 79.31 |
| TP_GPIOH3 | 360.93 | 440.72 | 81.900000000000006 |
| TP_GPIOH4 | 58.67 | 47.49 | 123.53 |
| TP_GPIOH5 | 235.92 | 295.72000000000003 | 79.78 |
| TP_GPIOH6 | 272.41000000000003 | 334.22 | 81.510000000000005 |
| TP_GPIOH7 | 71.86 | 61.57 | 116.72 |
| TP_IRQ_CPU_SERIAL | 467.61 | 562.07000000000005 | 83.19 |
| TP_JTAG_9716_SW1_TCK | 27.85 | 39.380000000000003 | 70.709999999999994 |
| TP_JTAG_9716_SW1_TDI | 27.85 | 39.380000000000003 | 70.709999999999994 |
| TP_JTAG_9716_SW1_TDO | 27.85 | 39.380000000000003 | 70.709999999999994 |
| TP_JTAG_9716_SW1_TMS | 27.85 | 39.380000000000003 | 70.709999999999994 |
| TP_LPC_CPU_CLKOUT0 | 385.22 | 493.09 | 78.12 |
| TP_LPC_CPU_FRAME_N | 302.3 | 390.1 | 77.489999999999995 |
| TP_STRAP_RSVD1 | 27.85 | 39.380000000000003 | 70.709999999999994 |
| TP_STRAP_RSVD3 | 27.85 | 39.380000000000003 | 70.709999999999994 |
| TP_STRAP_RSVD4 | 27.85 | 39.380000000000003 | 70.709999999999994 |
| TP_STRAP_RSVD5 | 27.85 | 39.380000000000003 | 70.709999999999994 |
| TP_STRAP_RSVD6 | 27.85 | 39.380000000000003 | 70.709999999999994 |
| TP_STRAP_RSVD7 | 27.85 | 39.380000000000003 | 70.709999999999994 |
| TP_STRAP_RSVD8 | 27.85 | 39.380000000000003 | 70.709999999999994 |
| TP_STRAP_RSVD9 | 27.85 | 39.380000000000003 | 70.709999999999994 |
| TP_STRAP_RSVD12 | 27.85 | 39.380000000000003 | 70.709999999999994 |
| TP_STRAP_RSVD13 | 27.85 | 39.380000000000003 | 70.709999999999994 |
| UART COUNT | 9561.2800000000007 | 8907.7800000000007 | 107.34 |
| USB_DN_R | 3248.88 | 3409.87 | 95.28 |
| USB_DP_R | 3248.88 | 3421.87 | 94.94 |
| USB_EN_1 | 3121.49 | 3317.84 | 94.08 |
| USB_EN_1_R | 416.89 | 541.73 | 76.95 |
| USB_OCS_N1 | 1812.97 | 2032.84 | 89.18 |
| USB_P1_F_DN1 | 746.38 | 681.35 | 109.54 |
| USB_P1_F_DP1 | 747.16 | 564.61 | 132.33000000000001 |
| USB_P2_DN | 80.739999999999995 | 65 | 124.22 |
| USB_P2_DP | 80.73 | 65 | 124.2 |
| V1P8_FG | 388.65 | 1061.8699999999999 | 36.6 |
| V1P8_FGA | 154.30000000000001 | 297.55 | 51.86 |
| VDD_DIFF | 506.75 | 2097.5700000000002 | 24.16 |
| XTAL_25MHZ_IN | 324.74 | 331.79 | 97.88 |
| XTAL_25MHZ_OUT | 180.85 | 202.47 | 89.32 |
| XTAL_25MHZ_R_OUT | 111.34 | 111.9 | 99.5 |
